G04 ================== begin FILE IDENTIFICATION RECORD ==================*
G04 Layout Name:  12432-1.brd*
G04 Film Name:    L8*
G04 File Format:  Gerber RS274X*
G04 File Origin:  Cadence Allegro 16.2-S037*
G04 Origin Date:  Wed Oct 17 11:00:15 2012*
G04 *
G04 Layer:  VIA CLASS/BOTTOM*
G04 Layer:  PIN/BOTTOM*
G04 Layer:  ETCH/BOTTOM*
G04 Layer:  DRAWING FORMAT/LAYER_PCB_STORY*
G04 Layer:  DRAWING FORMAT/LAYER_L8*
G04 *
G04 Offset:    (0.00 0.00)*
G04 Mirror:    No*
G04 Mode:      Positive*
G04 Rotation:  0*
G04 FullContactRelief:  No*
G04 UndefLineWidth:     6.00*
G04 ================== end FILE IDENTIFICATION RECORD ====================*
%FSLAX35Y35*MOIN*%
%IR0*IPPOS*OFA0.00000B0.00000*MIA0B0*SFA1.00000B1.00000*%
%ADD16O,.103X.06*%
%ADD20R,.23X.032*%
%AMMACRO18*
4,1,8,.197,-.186,
-.197,-.186,
-.197,.186,
.197,.186,
.197,.00925,
-.059,.00925,
-.059,-.00925,
.197,-.00925,
.197,-.186,
0.0*
%
%ADD18MACRO18*%
%ADD11C,.01*%
%ADD14R,.142X.028*%
%ADD15C,.022*%
%ADD12C,.028*%
%ADD10R,.05X.05*%
%ADD17R,.001X.001*%
%ADD13C,.315*%
%ADD19R,.394X.172*%
%ADD21C,.02*%
%ADD22C,.03*%
%ADD23C,.04*%
%ADD24C,.025*%
%ADD25C,.004*%
%ADD26C,.006*%
%ADD34O,.12702X.08402*%
%ADD28C,.05204*%
%ADD29C,.04604*%
%ADD32C,.09706*%
%ADD33C,.11506*%
%ADD31C,.17006*%
%ADD30R,.17206X.17204*%
%ADD27C,.33904*%
G75*
%LPD*%
G75*
G36*
G01X836134Y1881562D02*
X836194Y1881648D01*
X851918D01*
X865537Y1868030D01*
G02X865500Y1867431I-283J-283D01*
G03X864744Y1866385I1413J-1817D01*
G01X864697Y1866252D01*
X863498D01*
G03X856904Y1863521I0J-9327D01*
G01X855968Y1862584D01*
G03X855508Y1861995I2196J-2190D01*
G01X814349Y1793837D01*
X811602Y1789292D01*
X344763Y1016247D01*
G02X344075Y1016657I-343J207D01*
G01X846012Y1869583D01*
X846463Y1870348D01*
X847905D01*
X847954Y1870221D01*
G03X851627Y1869334I2145J835D01*
G01X851654Y1869358D01*
X851788Y1869410D01*
X851925Y1869356D01*
X851952Y1869331D01*
G03X853170Y1873314I1547J1705D01*
G03X849999Y1874452I-3172J-3851D01*
G01X846259D01*
G03X843028Y1872603I1J-3750D01*
G01X842789Y1872197D01*
X842413Y1871560D01*
X191215Y764996D01*
X157230Y714945D01*
G02X156499Y715170I-331J225D01*
G01X156531Y741456D01*
G02X156988Y742002I368J156D01*
G03Y751462I1083J4730D01*
G02X156499Y751852I-89J390D01*
G01Y766050D01*
X158715Y768266D01*
G02X159398Y767992I283J-283D01*
G03X162057Y770651I2601J58D01*
G02X161783Y771334I9J400D01*
G01X197399Y806950D01*
Y807399D01*
X198499Y808499D01*
Y894679D01*
G02X199180Y894963I400J0D01*
G03X202278Y894836I1619J1637D01*
G02X202823Y894807I257J-307D01*
G03X202814Y898404I1876J1803D01*
G02X202269Y898372I-290J276D01*
G03X199180Y898237I-1470J-1772D01*
G02X198499Y898521I-281J284D01*
G01Y1179550D01*
X174999Y1203050D01*
Y1289550D01*
G02X175412Y1289949I400J-1D01*
G03X177449Y1290827I87J2601D01*
G02X178049I300J-264D01*
G03X181915Y1294311I1950J1723D01*
G02Y1294852I294J271D01*
G03X181480Y1298753I-1916J1761D01*
G02Y1299410I227J328D01*
G03X181722Y1303500I-1481J2140D01*
G02Y1304100I264J300D01*
G03X178073Y1307799I-1722J1950D01*
G02X177473Y1307808I-296J269D01*
G03X175412Y1308714I-1975J-1695D01*
G02X174999Y1309113I-13J400D01*
G01Y1386050D01*
X177499Y1388550D01*
Y1435050D01*
X119999Y1492550D01*
Y1562959D01*
G02X120692Y1563231I400J0D01*
G03Y1566769I1908J1769D01*
G02X119999Y1567041I-293J272D01*
G01Y1621550D01*
X118600Y1622948D01*
Y1647522D01*
G02X120307Y1651642I5827J0D01*
G01X151707Y1683042D01*
G03X155950Y1693287I-10247J10245D01*
G01Y1801600D01*
X155951D01*
G03X154734Y1805596I-7170J0D01*
G01X154700Y1805647D01*
Y1807400D01*
X152100Y1810000D01*
Y1875200D01*
X150800Y1876500D01*
X124093D01*
X124072Y1876504D01*
G03X123112I-480J-2250D01*
G01X123091Y1876500D01*
X120900D01*
X119300Y1874900D01*
Y1846600D01*
X118224Y1845524D01*
X98524D01*
X98499Y1845550D01*
X35927D01*
X35726Y1845752D01*
X31427D01*
X31367Y1845824D01*
G03X27691Y1845638I-1768J-1474D01*
G01X27632Y1845550D01*
X4499D01*
X3199Y1846850D01*
Y1893048D01*
G02X3924Y1893280I400J0D01*
G03X33919Y1898134I13796J9852D01*
G02X34584Y1898299I382J-118D01*
G01X44034Y1888848D01*
X46611D01*
X46659Y1888819D01*
G03X49339I1340J2231D01*
G01X49387Y1888848D01*
X53298D01*
Y1879552D01*
X56501Y1876348D01*
X78501D01*
X78798Y1876052D01*
Y1867052D01*
X83001Y1862848D01*
X104497D01*
X108200Y1866552D01*
Y1891552D01*
X118497Y1901848D01*
X130997D01*
X138700Y1909552D01*
Y1950548D01*
X133582Y1955666D01*
G02X133865Y1956348I283J282D01*
G01X138997D01*
X140700Y1958052D01*
Y1983048D01*
X136497Y1987252D01*
X118001D01*
X114798Y1984048D01*
Y1973500D01*
X109500D01*
X109252Y1973252D01*
X99001D01*
X96501Y1970752D01*
X50001D01*
X45756Y1966506D01*
X42311Y1969950D01*
X38891D01*
X38843Y1969979D01*
G03X36155I-1344J-2230D01*
G01X36107Y1969950D01*
X20927D01*
G02X20644Y1970633I0J400D01*
G01X26328Y1976318D01*
X32180D01*
X32878Y1977015D01*
X32904Y1977029D01*
G03X30270Y1980771I-1106J2019D01*
G01X30213Y1980720D01*
X24504D01*
X6302Y1962518D01*
Y1949685D01*
G02X5813Y1949295I-400J0D01*
G03X3851Y1948836I-510J-2245D01*
G02X3199Y1949147I-252J311D01*
G01Y1988199D01*
X4000Y1989000D01*
X1029000D01*
X1029999Y1988001D01*
Y1745050D01*
X1030000Y1745049D01*
Y1696500D01*
X1028421Y1694921D01*
G02X1027741Y1695159I-283J283D01*
G03X1018344Y1685762I-8450J-947D01*
G02X1018582Y1685082I-45J-397D01*
G01X1013450Y1679950D01*
Y1675350D01*
X1012700Y1674600D01*
X975500D01*
X973901Y1673001D01*
X973827Y1672995D01*
G03X973381Y1668483I174J-2295D01*
G01X973431Y1668469D01*
X974400Y1667500D01*
X975748D01*
X975790Y1667355D01*
G03X980210Y1667356I2210J645D01*
G01X980252Y1667500D01*
X981901D01*
X981916Y1667316D01*
G03X986506I2295J184D01*
G01X986521Y1667500D01*
X1015500D01*
X1016000Y1667000D01*
Y1664900D01*
X1015600Y1664500D01*
X993000D01*
X991500Y1663000D01*
Y1662504D01*
X982425D01*
X982127Y1662802D01*
X977819D01*
X977803Y1662785D01*
X977706Y1662793D01*
G03X978551Y1658452I-206J-2293D01*
G01X978647Y1658501D01*
X978839Y1658394D01*
X978866Y1658352D01*
G03X983096Y1659433I1934J1248D01*
G01X983102Y1659510D01*
X983300Y1659700D01*
X991500D01*
Y1659000D01*
X993000Y1657500D01*
X1015300D01*
X1015900Y1656900D01*
Y1655300D01*
X1015100Y1654500D01*
X983248D01*
X983189Y1654564D01*
G03X979811I-1689J-1564D01*
G01X979752Y1654500D01*
X975400D01*
X973404Y1652504D01*
X969426D01*
X969366Y1652576D01*
G03X969370Y1649628I-1766J-1476D01*
G01X969430Y1649700D01*
X972400D01*
Y1649166D01*
G02X971935Y1648771I-400J0D01*
G03Y1644229I-377J-2271D01*
G02X972400Y1643834I65J-395D01*
G01Y1637965D01*
G02X972059Y1637823I-200J0D01*
G01X971884Y1637998D01*
X971893Y1638091D01*
G03X968017Y1639972I-2293J209D01*
G02X967359Y1640149I-275J290D01*
G03X962963Y1638781I-2209J-649D01*
G02X962453Y1638278I-380J-125D01*
G03X963889Y1636821I-751J-2176D01*
G02X964399Y1637324I380J125D01*
G03X966733Y1637828I752J2176D01*
G02X967391Y1637651I275J-290D01*
G03X969809Y1636007I2209J649D01*
G01X969902Y1636016D01*
X971217Y1634700D01*
X972400D01*
Y1624100D01*
X974000Y1622500D01*
X985859D01*
G03X988341I1241J2400D01*
G01X1014700D01*
X1015400Y1621800D01*
Y1620800D01*
X1014100Y1619500D01*
X988000D01*
X984600Y1616100D01*
Y1611800D01*
X987600Y1608800D01*
X1014000D01*
X1016100Y1606700D01*
Y1514700D01*
X1015000Y1513600D01*
X950100D01*
X944500Y1508000D01*
Y1434500D01*
X950400Y1428600D01*
X1017400D01*
X1020200Y1425800D01*
X1028200D01*
X1030000Y1424000D01*
Y1270500D01*
X1029999D01*
Y4000D01*
X1028999Y3000D01*
X139726D01*
G02X139500Y3730I0J400D01*
G03X120342I-9579J13986D01*
G02X120116Y3000I-226J-330D01*
G01X3999D01*
X3500Y3499D01*
Y354000D01*
X3475Y354025D01*
Y358025D01*
X11500Y366050D01*
X39378D01*
X58438Y346990D01*
G02X58598Y346605I-385J-386D01*
G01Y246950D01*
X58544Y246892D01*
G03X58098Y245765I1204J-1128D01*
G01Y243863D01*
G03X58544Y242736I1650J1D01*
G01X58598Y242678D01*
Y146237D01*
G03X60088Y142639I5088J-1D01*
G01X81050Y121677D01*
G03X86671Y119348I5622J5621D01*
G01X94971D01*
G03X100343Y121573I0J7598D01*
G01X103657Y124887D01*
X103771Y125000D01*
G02X105815Y125848I2044J-2040D01*
G01X113570D01*
X113593Y125674D01*
G03X117387Y127710I2283J299D01*
G02Y128313I262J302D01*
G03X113576Y130144I-1511J1737D01*
G01X113568Y129952D01*
X105814D01*
G03X100873Y127906I1J-6992D01*
G01X97441Y124475D01*
G02X94971Y123452I-2470J2471D01*
G01X86672D01*
G02X84096Y124442I0J3846D01*
G02X83947Y124584I2696J2978D01*
G01X64239Y144292D01*
X63915Y144615D01*
X62989Y145541D01*
G02X62700Y146238I697J697D01*
G01Y187470D01*
G02X63418Y187714I400J0D01*
G03X66748Y186074I3330J2561D01*
G01X71048D01*
G03Y194476I0J4201D01*
G01X66748D01*
G03X63418Y192836I0J-4201D01*
G02X62700Y193080I-318J244D01*
G01Y223173D01*
G02X63439Y223387I400J1D01*
G03X64465Y222102I6260J3947D01*
G01X91016Y195551D01*
G02X98598Y177250I-18300J-18303D01*
G01Y135049D01*
X98597Y135046D01*
G03Y134996I1401J-25D01*
G02X97588Y132561I-3444J1D01*
G02X92014Y130252I-5574J5573D01*
G01X90000D01*
X89600D01*
G02X89200Y130639I0J400D01*
G03X84701Y129884I-2301J-72D01*
G03X84698Y129767I2198J-115D01*
G03X85085Y128484I2318J-1D01*
G03X88780Y126012I1514J-1734D01*
G01X88826Y126148D01*
X92015D01*
G03X100490Y129659I-1J11986D01*
G03X102701Y134996I-5337J5337D01*
G01X102700D01*
Y177250D01*
G03X96606Y195371I-29986J1D01*
G02X97044Y195994I319J241D01*
G03X97999Y195848I956J3056D01*
G01X121673D01*
X139673Y177848D01*
X155999D01*
G03Y184252I0J3202D01*
G01X142325D01*
X124325Y202252D01*
X97999D01*
G03X94836Y198555I0J-3202D01*
G02X94155Y198213I-395J-62D01*
G03X93918Y198453I-21454J-20949D01*
G01X67367Y225004D01*
G02X66400Y227335I2330J2333D01*
G01Y288483D01*
G02X67135Y288702I400J0D01*
G03X67990Y287640I5830J3819D01*
G03X68038Y287589I1044J935D01*
G01X121981Y233647D01*
X122104Y233522D01*
G03X127828Y230619I7292J7284D01*
G01X127998Y230593D01*
Y230498D01*
X819160D01*
G03X825320Y233050I0J8712D01*
G01X840458Y248188D01*
X841346Y249074D01*
G02X841481Y249138I156J-154D01*
G01X845756D01*
X845811Y249026D01*
G03X849329Y248253I2067J1014D01*
G01X849369Y248286D01*
X849410Y248321D01*
X849542Y248372D01*
X849680Y248316D01*
X849707Y248291D01*
G03X850978Y252256I1571J1683D01*
G03X850724Y252483I-2396J-2426D01*
G01X850650Y252543D01*
Y252839D01*
X859116D01*
G02X859308Y252759I-1J-272D01*
G01X870908Y241159D01*
G03X874555Y239648I3647J3647D01*
G01X875816D01*
X875856Y239500D01*
G03X879725Y241711I2222J603D01*
G02Y242270I286J280D01*
G03X875780Y244021I-1647J1608D01*
G01X875775Y243944D01*
X875577Y243752D01*
X874273D01*
G02X874009Y243861I0J373D01*
G01X862209Y255661D01*
G03X859118Y256942I-3092J-3091D01*
G01X839875D01*
G03X834642Y254774I0J-7400D01*
G01X819514Y239648D01*
G02X816264Y238302I-3250J3252D01*
G01X152498D01*
G02X152128Y238854I0J400D01*
G03X151646Y241337I-2129J875D01*
G02Y241896I286J279D01*
G03X147868Y244376I-1647J1608D01*
G01X147817Y244252D01*
X140335D01*
X140240Y244291D01*
X133640Y250891D01*
G02X132900Y252676I1785J1786D01*
G01Y256550D01*
G03X131377Y260228I-5201J1D01*
G01X131008Y260597D01*
X128543Y263068D01*
X128537D01*
X82077Y309528D01*
G02X81200Y311644I2116J2117D01*
G01Y366051D01*
X81399Y366250D01*
Y369762D01*
X81432Y369812D01*
G03X81702Y370717I-1382J905D01*
G01Y372617D01*
G03X81432Y373522I-1652J0D01*
G01X81399Y373572D01*
Y378650D01*
X34499Y425550D01*
Y431002D01*
X67584D01*
G02X69080Y430469I0J-2367D01*
G01X72186Y427363D01*
G02X71829Y426687I-283J-283D01*
G03X71049Y426760I-780J-4128D01*
G01X66876D01*
X66873D01*
G03X66748Y418358I-125J-4200D01*
G01X71048D01*
G03X74160Y425381I0J4201D01*
G02X74457Y426050I296J269D01*
G01X74558D01*
X74583Y426043D01*
G03X76069Y425848I1485J5558D01*
G01X80694D01*
G03X82333Y426044I34J6670D01*
G01X82357Y426050D01*
X84499D01*
X89384Y430934D01*
X125163D01*
G02X125541Y430403I0J-400D01*
G03X126276Y427600I2458J-853D01*
G02Y427000I-264J-300D01*
G03X126059Y423316I1723J-1950D01*
G02Y422784I-299J-266D01*
G03X129939I1940J-1734D01*
G02Y423316I299J266D01*
G03X129722Y427000I-1940J1734D01*
G02Y427600I264J300D01*
G03X130457Y430403I-1723J1950D01*
G02X130835Y430934I378J131D01*
G01X276099D01*
G03X280580Y431394I-6J22111D01*
G03X280677Y431414I-4281J21007D01*
G03X283581Y432247I-4396J20803D01*
G03X283622Y432262I-461J1323D01*
G01X284355Y432556D01*
X833864Y653421D01*
X834950Y653861D01*
G03X835044Y653904I-536J1295D01*
G02X839297Y654898I4253J-8602D01*
G01X845513D01*
X845554Y654752D01*
G03X849341Y653685I2218J618D01*
G01X849368Y653710D01*
X849506Y653766D01*
X849638Y653715D01*
X849665Y653692D01*
G03X853461Y655185I1507J1740D01*
G02X854141Y655425I398J-43D01*
G01X862707Y646859D01*
G03X866636Y645232I3929J3929D01*
G01X876314D01*
X876349Y645075D01*
G03X880243Y647181I2247J498D01*
G02Y647740I286J279D01*
G03X876300Y649520I-1647J1608D01*
G01X876287Y649334D01*
X866639D01*
G02X865609Y649761I0J1457D01*
G01X854836Y660534D01*
G03X849603Y662702I-5234J-5233D01*
G01X835870D01*
G03X833654Y662362I2J-7402D01*
G01X206672Y465547D01*
X206600Y465600D01*
X205800D01*
X196100Y475300D01*
Y476570D01*
X779287Y1059756D01*
G02X781299Y1060590I2013J-2012D01*
G01X845111D01*
X845166Y1060478D01*
G03X848742Y1059754I2067J1014D01*
G02X849275Y1059746I262J-302D01*
G03X850526Y1063722I1558J1695D01*
G03X850446Y1063793I-2545J-2787D01*
G02X850652Y1064494I259J305D01*
G01X867280D01*
G02X867601Y1064360I-1J-453D01*
G01X867734Y1064229D01*
Y1055550D01*
G03X869189Y1052034I4972J-2D01*
G01X869386Y1051837D01*
G03X872749Y1050446I3360J3363D01*
G01X875002D01*
G03X876004Y1050522I0J6639D01*
G03X879821Y1052761I2229J573D01*
G01X879793Y1052789D01*
X879728Y1052935D01*
X879771Y1053058D01*
X879838Y1053148D01*
G03X875667Y1054641I-1874J1337D01*
G02X874999Y1054552I-666J2444D01*
G01X872712D01*
G02X872290Y1054741I36J647D01*
G01X872093Y1054938D01*
G02X871840Y1055550I612J611D01*
G01Y1064205D01*
G03X870615Y1067155I-4161J2D01*
G01X870498Y1067271D01*
G03X867281Y1068600I-3218J-3231D01*
G01X781489D01*
G03X773428Y1065261I0J-11401D01*
G01X199383Y491215D01*
G02X198700Y491498I-283J283D01*
G01Y496048D01*
X158997Y535752D01*
X151341D01*
G02X150995Y536351I1J400D01*
G03X151253Y537973I-1995J1149D01*
G01X151237Y538050D01*
X151318Y538184D01*
X151393Y538206D01*
G03X151856Y542435I-643J2210D01*
G02X151819Y543113I192J351D01*
G03X149394Y542981I-1319J1887D01*
G02X149431Y542303I-192J-351D01*
G03X148982Y541890I1320J-1886D01*
G01X148922Y541818D01*
X112765D01*
X111684Y542898D01*
X111693Y542991D01*
G03X107836Y544889I-2293J209D01*
G01X107700Y544836D01*
X107564Y544889D01*
G03X106209Y540907I-1564J-1689D01*
G01X106302Y540916D01*
X111119Y536098D01*
X143383D01*
G02X143666Y535416I0J-400D01*
G01X142298Y534048D01*
Y522052D01*
X146001Y518348D01*
X156501D01*
Y505451D01*
G03X156521Y505360I398J40D01*
G02X156324Y504872I-378J-131D01*
G03X156157Y504780I1171J-2324D01*
G01X156109Y504752D01*
X154887D01*
X154839Y504781D01*
G03X151549Y504273I-1340J-2231D01*
G02X150949I-300J264D01*
G03Y500827I-1950J-1723D01*
G02X151549I300J-264D01*
G03X154839Y500319I1950J1723D01*
G01X154887Y500348D01*
X156109D01*
X156157Y500320D01*
G03X156324Y500228I1338J2232D01*
G02X156521Y499740I-181J-357D01*
G03X156501Y499649I378J-131D01*
G01Y496452D01*
X142543D01*
G02X142271Y497144I1J400D01*
G03X138679Y500909I-1772J1905D01*
G02X138119I-280J286D01*
G03X134527Y497144I-1820J-1860D01*
G02X134255Y496452I-273J-292D01*
G01X126194D01*
X126134Y496538D01*
G03X121864I-2135J-1488D01*
G01X121804Y496452D01*
X110194D01*
G02X109795Y496881I0J400D01*
G03X105203I-2296J169D01*
G02X104804Y496452I-399J-29D01*
G01X83034D01*
X77100Y502385D01*
Y502431D01*
X67068Y512463D01*
X67269Y512664D01*
G03X65837Y516540I-1669J1586D01*
G02X65596Y517220I42J398D01*
G01X76040Y527663D01*
X76171Y527810D01*
X78047Y530098D01*
X80999Y533050D01*
X83232Y535786D01*
G02X83935Y535606I310J-253D01*
G03X84552Y534417I2263J420D01*
G02Y533858I-286J-279D01*
G03X87846I1647J-1608D01*
G02Y534417I286J279D01*
G03X86156Y538327I-1647J1608D01*
G02X85839Y538979I-7J400D01*
G01X156499Y625550D01*
Y625761D01*
X836725Y1455221D01*
X846498Y1464994D01*
G02X847093Y1464961I283J-283D01*
G03X850398Y1464665I1795J1441D01*
G01X850425Y1464688D01*
X850557Y1464739D01*
X850695Y1464683D01*
X850722Y1464658D01*
G03X851928Y1468620I1566J1688D01*
G03X851213Y1469102I-3878J-4982D01*
G02X851413Y1469848I200J346D01*
G01X853608D01*
G02X856358Y1468709I0J-3890D01*
G01X867158Y1457909D01*
G03X871650Y1456048I4492J4492D01*
G01X875781D01*
X875819Y1455896D01*
G03X879613Y1458144I2235J554D01*
G01X879583Y1458172D01*
X879516Y1458320D01*
X879567Y1458453D01*
X879590Y1458480D01*
G03X875575Y1460323I-1737J1511D01*
G01X875550Y1460152D01*
X871156D01*
G02X870409Y1460461I0J1056D01*
G01X859478Y1471392D01*
G03X853299Y1473952I-6180J-6179D01*
G01X835442D01*
G03X831238Y1472210I1J-5946D01*
G01X825036Y1466009D01*
G02X824361Y1466367I-282J283D01*
G03X822533Y1464539I-2261J433D01*
G02X822891Y1463864I75J-393D01*
G01X816987Y1457959D01*
X816113Y1456880D01*
X156765Y643346D01*
X156499Y643440D01*
X156430Y643464D01*
X128391Y608336D01*
X64742Y529803D01*
X63258Y528130D01*
X46850Y511722D01*
X44499Y511050D01*
X37699D01*
X37099Y511650D01*
Y515150D01*
X37890Y515941D01*
X37901Y515949D01*
G03X38325Y516373I-1402J1826D01*
G01X38333Y516384D01*
X39169Y517220D01*
X39183Y517230D01*
G03X39776Y517731I-2684J3778D01*
G01X41095Y519050D01*
X41286Y519238D01*
X41294Y519244D01*
G03X41537Y519499I-885J1087D01*
G01X85665Y579270D01*
X125174Y644691D01*
G02X125884Y644642I342J-207D01*
G03X129100Y643528I2115J908D01*
G01X129199Y643582D01*
X129396Y643467D01*
X129422Y643422D01*
G03X130300Y646622I1978J1178D01*
G01X130200Y646568D01*
X130003Y646683D01*
X129977Y646728D01*
G03X127818Y647845I-1978J-1178D01*
G02X127444Y648450I-32J399D01*
G01X154908Y693928D01*
X156499Y696550D01*
Y696563D01*
X160093Y702514D01*
X161630Y705060D01*
X164341Y709547D01*
X175121Y727401D01*
X197813Y760819D01*
X293659Y923686D01*
X815114Y1787169D01*
X818426Y1792649D01*
X858959Y1859772D01*
X859806Y1860619D01*
G02X863498Y1862148I3693J-3694D01*
G01X864214D01*
G02X864613Y1861761I-1J-400D01*
G03X868561Y1863448I2301J79D01*
G02Y1864007I286J280D01*
G03X868731Y1864201I-1644J1612D01*
G02X869329Y1864239I316J-245D01*
G01X916098Y1817469D01*
Y1798377D01*
G03X918900I1401J-1827D01*
G01Y1818631D01*
X870403Y1867129D01*
X869823Y1868526D01*
X868426Y1869105D01*
X856303Y1881228D01*
G02X856324Y1881812I283J282D01*
G03X852747Y1884564I-1510J1738D01*
G01X852692Y1884452D01*
X836194D01*
X836134Y1884538D01*
G03X831864I-2135J-1488D01*
G01X831804Y1884452D01*
X818110D01*
X796042Y1906519D01*
G02X796218Y1907188I282J283D01*
G03X797452Y1911446I-692J2508D01*
G02X797448Y1911978I296J268D01*
G03X797437Y1915426I-1955J1718D01*
G02X797438Y1915959I299J266D01*
G03X797292Y1919584I-1937J1737D01*
G02X797291Y1920164I275J290D01*
G03X793708Y1920162I-1793J1886D01*
G02X793709Y1919582I-275J-290D01*
G03X793557Y1915966I1792J-1887D01*
G02X793556Y1915433I-299J-266D01*
G03X793567Y1911946I1937J-1737D01*
G02X793571Y1911414I-296J-268D01*
G03X793018Y1910388I1956J-1716D01*
G02X792349Y1910212I-386J106D01*
G01X784400Y1918161D01*
Y1935223D01*
G03X781598I-1401J1827D01*
G01Y1916999D01*
X816948Y1881648D01*
X831804D01*
X831864Y1881562D01*
G03X836134I2135J1488D01*
G37*
G36*
G01X5499Y689650D02*
X5299Y689850D01*
Y710850D01*
X7101Y712652D01*
X7230Y712586D01*
G03X7558Y722990I2613J5125D01*
G02X6999Y723357I-159J367D01*
G01Y741550D01*
X10999Y745550D01*
X51499D01*
X58999Y738050D01*
Y724500D01*
X31084Y696585D01*
X30958Y696643D01*
G03X28418Y696223I-959J-2093D01*
G02X27826Y696271I-274J291D01*
G03X26624Y692654I-1827J-1401D01*
G01X26737Y692686D01*
X26961Y692462D01*
X26549Y692050D01*
X22999D01*
X20599Y689650D01*
X5499D01*
G37*
G36*
G01X78999Y1587550D02*
X75999Y1590550D01*
X45499D01*
X36999Y1599050D01*
Y1614824D01*
X37014Y1614861D01*
G03Y1616607I-2130J873D01*
G01X36999Y1616644D01*
Y1630222D01*
X37009Y1630252D01*
G03Y1631654I-2193J701D01*
G01X36999Y1631684D01*
Y1663204D01*
Y1663208D01*
G03Y1663392I-2300J92D01*
G01Y1663396D01*
Y1671050D01*
X34991Y1673058D01*
X34997Y1673148D01*
G03X32233Y1675554I-2297J152D01*
G01X32213Y1675550D01*
X24005D01*
X23960Y1675574D01*
G03X21768I-1096J-2024D01*
G01X21723Y1675550D01*
X21699D01*
X21663Y1675514D01*
X21644Y1675502D01*
G03X20912Y1674770I1220J-1952D01*
G01X20900Y1674751D01*
X20005Y1673856D01*
X5393D01*
X5099Y1674150D01*
Y1693650D01*
X7971Y1696522D01*
X8087Y1696485D01*
G03X15587Y1701659I1756J5478D01*
G01X15597Y1701848D01*
X53701D01*
X55965Y1699584D01*
G02X55682Y1698902I-283J-282D01*
G01X32329D01*
X32269Y1698973D01*
G03Y1696027I-1769J-1473D01*
G01X32329Y1696098D01*
X59450D01*
X63500Y1692049D01*
Y1641761D01*
X63457Y1641706D01*
G03Y1636484I3291J-2611D01*
G01X63500Y1636429D01*
Y1629050D01*
X70499Y1622051D01*
Y1622050D01*
X71499Y1621050D01*
X90999D01*
X96999Y1615050D01*
Y1588550D01*
X95999Y1587550D01*
X78999D01*
G37*
G36*
G01X40452Y1755406D02*
G03X39975Y1753900I1823J-1406D01*
G02X39624Y1753485I-400J-18D01*
G03X39150Y1749024I277J-2285D01*
G02X39342Y1748409I-131J-378D01*
G03X41950Y1749226I1858J-1359D01*
G02X41758Y1749841I131J378D01*
G03X42200Y1751300I-1858J1359D01*
G02X42551Y1751715I400J18D01*
G03X43825Y1755702I-276J2285D01*
G01X43759Y1755762D01*
Y1756050D01*
X44142D01*
X44200Y1755994D01*
G03X47398I1599J1656D01*
G01X47456Y1756050D01*
X60999D01*
X78999Y1738050D01*
Y1703050D01*
X99499Y1682550D01*
Y1655550D01*
X102598Y1652452D01*
Y1624148D01*
X100999Y1622550D01*
X73499D01*
X64999Y1631050D01*
Y1634696D01*
G02X65516Y1635078I400J0D01*
G03X66748Y1634894I1230J4017D01*
G01X71048D01*
G03Y1643296I0J4201D01*
G01X66748D01*
G03X65516Y1643112I-2J-4201D01*
G02X64999Y1643494I-117J382D01*
G01Y1693050D01*
X62292Y1695757D01*
G02X62433Y1696098I141J141D01*
G01X62805D01*
X62865Y1696013D01*
G03X67135I2135J1487D01*
G01X67195Y1696098D01*
X71819D01*
X73098Y1694819D01*
Y1693829D01*
X73027Y1693769D01*
G03X75973I1473J-1769D01*
G01X75902Y1693829D01*
Y1695981D01*
X72981Y1698902D01*
X67195D01*
X67135Y1698987D01*
G03X62865I-2135J-1487D01*
G01X62805Y1698902D01*
X59148D01*
X54999Y1703050D01*
X15494D01*
X15459Y1703207D01*
G03X4567Y1704255I-5616J-1244D01*
G02X3917Y1704132I-367J160D01*
G01X3499Y1704550D01*
Y1754250D01*
X5299Y1756050D01*
X40135D01*
G02X40452Y1755406I0J-400D01*
G37*
G36*
G01X3924Y1912984D02*
G02X3199Y1913216I-325J232D01*
G01Y1934244D01*
G02X3882Y1934527I400J0D01*
G01X6260Y1932148D01*
X6735D01*
X11436Y1927448D01*
X15218D01*
X15277Y1927357D01*
G03X16826Y1926256I2178J1424D01*
G01X16880Y1926243D01*
X20750Y1922372D01*
X20740Y1922277D01*
G03X21381Y1920432I2290J-238D01*
G02X21017Y1919760I-286J-279D01*
G03X3924Y1912984I-3298J-16628D01*
G37*
G36*
G01X17796Y1935733D02*
X20500Y1938438D01*
Y1957662D01*
X19200Y1958962D01*
Y1959498D01*
X19248Y1959554D01*
G03X19766Y1960653I-1749J1496D01*
G01X19777Y1960715D01*
X21410Y1962348D01*
X30683D01*
G02X31026Y1961741I0J-400D01*
G03X30789Y1959909I1973J-1187D01*
G01X30798Y1959882D01*
Y1958243D01*
X30769Y1958196D01*
G03X35229I2230J-1341D01*
G01X35200Y1958243D01*
Y1959882D01*
X35209Y1959909D01*
G03X34972Y1961741I-2210J645D01*
G02X35315Y1962348I343J207D01*
G01X39161D01*
X41429Y1960079D01*
X41443Y1960054D01*
G03X44259Y1959000I2019J1106D01*
G02X44798Y1958625I139J-375D01*
G01Y1955052D01*
X46501Y1953348D01*
X54000D01*
Y1953000D01*
X56500Y1950500D01*
Y1949500D01*
X56000Y1949000D01*
Y1945000D01*
X52000Y1941000D01*
X44500D01*
X42000Y1938500D01*
Y1928128D01*
G02X41317Y1927845I-400J0D01*
G01X38059Y1931103D01*
X38046Y1931157D01*
G03X36150Y1933053I-2525J-629D01*
G01X36096Y1933066D01*
X27700Y1941462D01*
Y1955377D01*
X27709Y1955404D01*
G03X23289I-2210J646D01*
G01X23298Y1955377D01*
Y1939638D01*
X27202Y1935733D01*
G02X26919Y1935051I-283J-282D01*
G01X25387D01*
X25340Y1935079D01*
G03X22658I-1341J-2230D01*
G01X22611Y1935050D01*
X18079D01*
G02X17796Y1935733I0J400D01*
G37*
G36*
G01X36846Y458703D02*
X29499Y466050D01*
Y491050D01*
X32443Y493994D01*
X39269D01*
G03X40167Y494049I-8J7486D01*
G01X40179Y494050D01*
X41999D01*
X42862Y494913D01*
X42887Y494927D01*
G03X44562Y496187I-3618J6553D01*
G01X62629Y514253D01*
G02X63309Y514012I282J-283D01*
G03X64126Y512481I2290J238D01*
G01X64198Y512421D01*
Y511369D01*
X74298Y501269D01*
Y501223D01*
X81872Y493648D01*
X121804D01*
X121864Y493563D01*
G03X126134I2135J1487D01*
G01X126194Y493648D01*
X170924D01*
G02X171157Y492924I0J-400D01*
G03X173841I1342J-1871D01*
G02X174074Y493648I233J324D01*
G01X174500D01*
X174527Y493481D01*
G03X176590Y496143I2272J369D01*
G01X176497Y496134D01*
X176180Y496452D01*
X175724D01*
G02X175330Y496923I0J400D01*
G02X177184Y498778I2265J-410D01*
G03X177395Y498889I-72J393D01*
G02X177961I283J-283D01*
G01X186798Y490052D01*
Y486466D01*
X186710Y486406D01*
G03X186525Y486268I1282J-1912D01*
G02X185994Y486285I-256J307D01*
G03X186090Y482612I-1794J-1885D01*
G02X186620Y482657I290J-275D01*
G03X190279Y484177I1380J1843D01*
G01X190304Y484348D01*
X191551D01*
G02X191834Y483666I0J-400D01*
G01X178823Y470656D01*
X178822D01*
X177933Y469766D01*
G02X172225Y467402I-5708J5708D01*
G01X50408D01*
G03X43695Y464850I2J-10110D01*
G01X43657Y464817D01*
X43628Y464810D01*
X38259Y459441D01*
G02X36846Y458703I-1883J1885D01*
G37*
G36*
G01X32768Y1912433D02*
G02X32031Y1912219I-400J1D01*
G03X23563Y1919045I-14310J-9087D01*
G02X23602Y1919808I138J375D01*
G03X24580Y1920336I-572J2230D01*
G02X25133Y1920322I269J-296D01*
G03X27411Y1919735I1633J1623D01*
G01X27438Y1919744D01*
X28679D01*
X32768Y1915654D01*
Y1912433D01*
G37*
G36*
G01X77141Y1532908D02*
X101724Y1508324D01*
Y1473679D01*
G02X101231Y1473290I-400J0D01*
G03Y1468810I-532J-2240D01*
G02X101724Y1468421I93J-389D01*
G01Y1441724D01*
X100024Y1440024D01*
X53996Y1486053D01*
G02X52499Y1488463I6160J5496D01*
G01Y1513050D01*
X50626Y1514923D01*
X50613Y1514946D01*
G03X49333Y1516720I-8653J-4895D01*
G01X49315Y1516741D01*
X49298Y1516774D01*
X41500Y1524571D01*
Y1533072D01*
X41702Y1533273D01*
Y1533429D01*
X42486Y1534214D01*
X57736D01*
X57794Y1534120D01*
G03X60214Y1532907I2206J1380D01*
G01X60222Y1532908D01*
X77141D01*
G37*
G36*
G01X54499Y1898550D02*
X61499Y1905550D01*
X72999D01*
X76474Y1909026D01*
X87026D01*
X93000Y1915000D01*
Y1946551D01*
X101999Y1955550D01*
X131999D01*
X137499Y1950050D01*
Y1910050D01*
X130499Y1903050D01*
X117999D01*
X106999Y1892050D01*
Y1867050D01*
X103999Y1864050D01*
X83499D01*
X79999Y1867550D01*
Y1876550D01*
X78999Y1877550D01*
X56999D01*
X54499Y1880050D01*
Y1898550D01*
G37*
G36*
G01X55449Y1937000D02*
X69499Y1951050D01*
X84499D01*
X89499Y1946050D01*
Y1917050D01*
X84999Y1912550D01*
X75499D01*
X71974Y1909026D01*
X59975D01*
X55499Y1904550D01*
X47000D01*
X45500Y1906050D01*
Y1936500D01*
X46000Y1937000D01*
X55449D01*
G37*
G36*
G01X46999Y1954550D02*
X45999Y1955550D01*
Y1965050D01*
X50499Y1969550D01*
X96999D01*
X99499Y1972050D01*
X108999D01*
X112499Y1968550D01*
Y1959050D01*
X110999Y1957550D01*
X94499D01*
X91499Y1954550D01*
X46999D01*
G37*
G36*
G01X130598Y238301D02*
G02X127919Y239411I1J3790D01*
G01X127240Y240091D01*
X74290Y293041D01*
G02X73800Y294223I1182J1182D01*
G01Y306203D01*
G02X74546Y306405I400J1D01*
G03X75851Y304715I7228J4233D01*
G01X125005Y255561D01*
X125098Y255468D01*
Y252752D01*
X124705D01*
X124686Y252930D01*
G03X120975Y250878I-2289J-242D01*
G02X121007Y250595I-124J-157D01*
G03X125009Y248505I1792J-1445D01*
G01X125051Y248648D01*
X125499D01*
G03X128570Y250284I0J3700D01*
G02X129273Y250209I332J-223D01*
G03X130264Y248517I6152J2467D01*
G03X130738Y247989I5162J4157D01*
G01X137338Y241389D01*
G03X140334Y240148I2997J2997D01*
G01X147289D01*
G02X147697Y239746I8J-400D01*
G03X147870Y238854I2302J-16D01*
G02X147500Y238301I-370J-153D01*
G01X130598D01*
G37*
G36*
G01X116999Y1957550D02*
X115999Y1958550D01*
Y1983550D01*
X118499Y1986050D01*
X126337D01*
X126397Y1985968D01*
G03X130603I2103J1532D01*
G01X130663Y1986050D01*
X135999D01*
X139499Y1982550D01*
Y1958550D01*
X138499Y1957550D01*
X116999D01*
G37*
G36*
G01X190052Y485550D02*
X189994Y485650D01*
G03X187999Y486802I-1994J-1150D01*
G01Y490550D01*
X158999Y519550D01*
X146499D01*
X143499Y522550D01*
Y533550D01*
X144499Y534550D01*
X158499D01*
X197499Y495550D01*
Y489550D01*
X193499Y485550D01*
X190052D01*
G37*
G36*
G01X844859Y1469488D02*
G02X844967Y1469120I0J-200D01*
G03X844218Y1468517I2430J-3785D01*
G01X833676Y1457975D01*
X157208Y633097D01*
G02X156499Y633351I-309J254D01*
G01Y635927D01*
X819581Y1454070D01*
X820309Y1454967D01*
X834395Y1469054D01*
G02X835443Y1469488I1048J-1048D01*
G01X844859D01*
G37*
G36*
G01X170163Y435037D02*
X169700Y435500D01*
Y443654D01*
X169809Y443709D01*
G03X170733Y444200I-14668J28719D01*
G02X170811Y444242I1906J-3447D01*
G03X171064Y444412I-651J1242D01*
G01X172360Y445504D01*
X172361D01*
X181448Y453159D01*
X181905Y453434D01*
X182333Y453605D01*
X832207Y657607D01*
G02X832342Y657231I59J-191D01*
G01X832328Y657225D01*
X282233Y436127D01*
G02X279836Y435420I-5481J14167D01*
G02X276100Y435037I-3737J18036D01*
G01X170163D01*
G37*
G36*
G01X1016200Y1432800D02*
X1014700Y1431300D01*
X952200D01*
X948000Y1435500D01*
Y1506800D01*
X952200Y1511000D01*
X1015400D01*
X1016200Y1510200D01*
Y1432800D01*
G37*
%LPC*%
G75*
G36*
G01X805558Y1149620D02*
X805510Y1149648D01*
X803873D01*
X803846Y1149640D01*
G02Y1154060I-647J2210D01*
G01X803873Y1154052D01*
X805510D01*
X805558Y1154080D01*
G02Y1149620I1341J-2230D01*
G37*
G36*
G01X837052Y1949413D02*
X837000Y1949356D01*
Y1947621D01*
X837008Y1947593D01*
G02X832589Y1947599I-2210J-643D01*
G01X832598Y1947627D01*
Y1950486D01*
X832591Y1950511D01*
G02X834950Y1953747I2523J639D01*
G02X837052Y1949413I164J-2597D01*
G37*
G36*
G01X305847Y25198D02*
X290702D01*
X288298Y27603D01*
Y32219D01*
G03X287725Y32580I-400J0D01*
G02X286700Y37528I-1122J2348D01*
G03X287086Y38077I15J400D01*
G02X291930Y39977I2413J973D01*
G03X292587Y39837I374J143D01*
G01X303001Y50252D01*
X311497D01*
X313200Y48548D01*
Y32552D01*
X305847Y25198D01*
G37*
G36*
G01X896115Y35467D02*
X895997Y35348D01*
X839001D01*
X834798Y39552D01*
Y76548D01*
X836550Y78300D01*
X833798Y81052D01*
Y126548D01*
X837501Y130252D01*
X892497D01*
X894700Y128048D01*
X894701Y121331D01*
G03X895383Y121048I400J0D01*
G01X898087Y123752D01*
X903111D01*
X903158Y123780D01*
G02X905840I1341J-2230D01*
G01X905887Y123752D01*
X907587D01*
X908721Y124885D01*
X908732Y124947D01*
G02X911645Y126760I2268J-397D01*
G01X911672Y126752D01*
X912718D01*
G03X913001Y127434I0J400D01*
G01X910837Y129598D01*
X908172D01*
X908145Y129590D01*
G02Y134010I-646J2210D01*
G01X908172Y134002D01*
X912661D01*
X920117Y126545D01*
X920171Y126532D01*
G02X922067Y124636I-629J-2525D01*
G01X922080Y124582D01*
X924126Y122536D01*
G03X924792Y122705I283J283D01*
G02X926602Y124317I2207J-655D01*
G01X926664Y124328D01*
X930087Y127752D01*
X950497D01*
X962143Y116105D01*
X962197Y116092D01*
G02X964093Y114196I-629J-2525D01*
G01X964106Y114142D01*
X970900Y107348D01*
Y91338D01*
X965411Y85848D01*
X955749D01*
X955646Y85602D01*
X955700Y85548D01*
Y33552D01*
X951497Y29348D01*
X926501D01*
X924383Y31467D01*
G03X923701Y31184I-282J-283D01*
G01X923700Y17052D01*
X920497Y13848D01*
X900001D01*
X896798Y17052D01*
Y35184D01*
G03X896115Y35467I-400J0D01*
G37*
G36*
G01X109133Y73349D02*
X108001D01*
X105798Y75552D01*
Y114548D01*
X111001Y119752D01*
X179997D01*
X182200Y117548D01*
Y109331D01*
G03X182883Y109048I400J0D01*
G01X185387Y111552D01*
X193111D01*
X193158Y111580D01*
G02X195840I1341J-2230D01*
G01X195887Y111552D01*
X206861D01*
X206905Y111576D01*
G02X208048Y111851I1092J-2026D01*
G01X208133Y111850D01*
X209535Y113251D01*
X214918D01*
G03X215201Y113934I0J400D01*
G01X214787Y114348D01*
X205887D01*
X205840Y114320D01*
G02X203158I-1341J2230D01*
G01X203111Y114348D01*
X197087D01*
X192837Y118598D01*
X189672D01*
X189645Y118590D01*
G02Y123010I-646J2210D01*
G01X189672Y123002D01*
X194661D01*
X198911Y118752D01*
X203111D01*
X203158Y118780D01*
G02X205840I1341J-2230D01*
G01X205887Y118752D01*
X216611D01*
X225700Y109662D01*
Y108823D01*
X225709Y108796D01*
G02X225801Y108151I-2210J-644D01*
G03X226201Y107752I400J1D01*
G01X235487D01*
X235866Y108131D01*
X235880Y108156D01*
G02X235960Y108291I2019J-1105D01*
G01X235992Y108340D01*
Y108598D01*
X234422D01*
X234395Y108590D01*
G02Y113010I-646J2210D01*
G01X234422Y113002D01*
X239587D01*
X243300Y109288D01*
Y96438D01*
X243329Y96391D01*
G02Y93709I-2230J-1341D01*
G01X243300Y93662D01*
Y85738D01*
X232782Y75219D01*
X232768Y75194D01*
G02X232573Y74896I-2018J1108D01*
G03X232890Y74252I317J-244D01*
G01X235497D01*
X237200Y72548D01*
Y32552D01*
X234497Y29848D01*
X214501D01*
X213883Y30467D01*
G03X213200Y30184I-283J-283D01*
G01Y20052D01*
X210497Y17348D01*
X187001D01*
X182798Y21552D01*
Y37348D01*
X109501D01*
X105798Y41052D01*
Y69048D01*
X109416Y72666D01*
G03X109133Y73349I-283J283D01*
G37*
G36*
G01X307042Y1966434D02*
G02X304956I-1043J-2384D01*
G03Y1967166I-161J366D01*
G02X307042I1043J2384D01*
G03Y1966434I161J-366D01*
G37*
G36*
G01X771383Y1929007D02*
G02Y1931093I-2384J1043D01*
G03X772115I366J161D01*
G02Y1929007I2384J-1043D01*
G03X771383I-366J-161D01*
G37*
G36*
G01X164743Y1792490D02*
G02X163649Y1790980I1157J-1990D01*
G03X163057Y1791410I-391J84D01*
G02X164151Y1792920I-1157J1990D01*
G03X164743Y1792490I391J-84D01*
G37*
G36*
G01X754634Y1764060D02*
G02X751271Y1768029I-1734J1940D01*
G03X751359Y1768555I-250J312D01*
G02X754997Y1772114I2199J1391D01*
G03X755525Y1772190I222J333D01*
G02X755657Y1772335I1989J-1678D01*
G03X755454Y1773006I-286J280D01*
G02X754265Y1773610I545J2544D01*
G03X753733I-266J-299D01*
G02X750370Y1777579I-1734J1940D01*
G03X750458Y1778105I-250J312D01*
G02X754096Y1781664I2199J1391D01*
G03X754624Y1781740I222J333D01*
G02X758027Y1777880I1993J-1673D01*
G03X757944Y1777278I216J-337D01*
G02X757860Y1773732I-1945J-1728D01*
G03X758063Y1773061I286J-280D01*
G02X758928Y1768330I-545J-2544D01*
G03X758845Y1767728I216J-337D01*
G02X755166Y1764060I-1946J-1728D01*
G03X754634I-266J-299D01*
G37*
G36*
G01X352068Y1582709D02*
G02X351080Y1584795I-2294J191D01*
G03X351706Y1585091I227J329D01*
G02X352694Y1583005I2294J-191D01*
G03X352068Y1582709I-227J-329D01*
G37*
G36*
G01X129306Y1567294D02*
G02X127247Y1566527I-206J-2594D01*
G03X126994Y1567206I-285J280D01*
G02X129053Y1567973I206J2594D01*
G03X129306Y1567294I285J-280D01*
G37*
G36*
G01X564542Y1488934D02*
G02X562456I-1043J-2384D01*
G03Y1489666I-161J366D01*
G02Y1494434I1043J2384D01*
G03Y1495166I-161J366D01*
G02X564542I1043J2384D01*
G03Y1494434I161J-366D01*
G02Y1489666I-1043J-2384D01*
G03Y1488934I161J-366D01*
G37*
G36*
G01X868953Y1373429D02*
X868906Y1373458D01*
X866576D01*
X866467Y1373497D01*
X866439Y1373499D01*
G02X864515Y1374811I157J2297D01*
G03X863813Y1374849I-361J-171D01*
G02X860376Y1377819I-1964J1201D01*
G01X860448Y1377879D01*
Y1381305D01*
X860362Y1381365D01*
G02Y1385635I1487J2135D01*
G01X860448Y1385695D01*
Y1434481D01*
X881848Y1455881D01*
Y1470219D01*
X870068Y1481998D01*
X797568D01*
X787698Y1491869D01*
Y1523869D01*
X784801Y1526766D01*
X784708Y1526757D01*
G02X786792Y1528841I-209J2293D01*
G01X786783Y1528748D01*
X790500Y1525031D01*
Y1493031D01*
X798730Y1484802D01*
X812231D01*
G03X812597Y1485364I1J400D01*
G02X816803I2103J936D01*
G03X817169Y1484802I365J-162D01*
G01X871230D01*
X884650Y1471381D01*
Y1454719D01*
X863250Y1433319D01*
Y1385695D01*
X863336Y1385635D01*
G02Y1381365I-1487J-2135D01*
G01X863250Y1381305D01*
Y1377879D01*
X863322Y1377819D01*
G02X863930Y1377035I-1472J-1770D01*
G03X864632Y1376997I361J171D01*
G02X865094Y1377540I1963J-1202D01*
G03X865109Y1378132I-261J303D01*
G02X868358Y1378199I1591J1664D01*
G01X868302Y1378141D01*
Y1377860D01*
X868906D01*
X868953Y1377889D01*
G02Y1373429I1341J-2230D01*
G37*
G36*
G01X750629Y1113044D02*
G02X746802Y1113523I-2130J-1494D01*
G03X746869Y1114056I-261J303D01*
G02X747597Y1117742I2130J1494D01*
G03X747731Y1118275I-215J337D01*
G02X752475Y1120350I2268J1275D01*
G03X753208Y1120283I381J123D01*
G02X753023Y1118250I2291J-1233D01*
G03X752290Y1118317I-381J-123D01*
G02X751401Y1117358I-2291J1233D01*
G03X751267Y1116825I215J-337D01*
G02X750696Y1113577I-2268J-1275D01*
G03X750629Y1113044I261J-303D01*
G37*
G36*
G01X68913Y543973D02*
G02X65013Y545135I-2413J-973D01*
G01X65098Y545195D01*
Y545581D01*
X65716Y546198D01*
X65707Y546291D01*
G02X70266Y546907I2293J209D01*
G03X70932Y546685I394J71D01*
G02X70992Y546739I1570J-1684D01*
G03X71014Y547019I-131J151D01*
G02X74487Y546565I1986J1681D01*
G01X74402Y546505D01*
Y546299D01*
X74434Y546249D01*
G02X70234Y544593I-1934J-1249D01*
G03X69568Y544815I-394J-71D01*
G02X69094Y544475I-1568J1685D01*
G03X68913Y543973I190J-352D01*
G37*
G36*
G01X189222Y533563D02*
G02X185776I-1723J-1950D01*
G03Y534163I-264J300D01*
G02X186918Y538649I1723J1950D01*
G03X187118Y539315I-89J390D01*
G02X187276Y543063I1881J1798D01*
G03Y543663I-264J300D01*
G02X187059Y547347I1723J1950D01*
G03Y547879I-299J266D01*
G02X190949Y551336I1940J1734D01*
G03X191549I300J264D01*
G02X195605Y548085I1950J-1723D01*
G03X195671Y547543I323J-236D01*
G02X195511Y543432I-1672J-1994D01*
G03X195444Y542841I232J-326D01*
G02X191549Y539390I-1945J-1728D01*
G03X190949I-300J-264D01*
G02X189580Y538577I-1949J1723D01*
G03X189380Y537911I89J-390D01*
G02X189222Y534163I-1881J-1798D01*
G03Y533563I264J-300D01*
G37*
G36*
G01X810813Y294738D02*
G02X807933I-1440J-2167D01*
G03Y295404I-222J333D01*
G02X808162Y299874I1440J2167D01*
G03X808112Y300604I-186J354D01*
G02X807462Y305150I887J2446D01*
G03X807512Y305752I-236J323D01*
G02X810910Y305471I1861J1819D01*
G03X810860Y304869I236J-323D01*
G02X810210Y300747I-1861J-1819D01*
G03X810260Y300017I186J-354D01*
G02X810813Y295404I-887J-2446D01*
G03Y294738I222J-333D01*
G37*
G36*
G01X252398Y293179D02*
X252470Y293239D01*
Y303003D01*
X277802Y328335D01*
X277784Y328438D01*
G02X280803Y331457I2561J458D01*
G01X280906Y331439D01*
X285136Y335669D01*
G03X284875Y336351I-283J283D01*
G02X283436Y336960I124J2299D01*
G03X283156Y336952I-136J-147D01*
G02X283062Y340240I-1657J1598D01*
G03X283342Y340248I136J147D01*
G02X283455Y340358I1661J-1594D01*
G03X283441Y340666I-134J148D01*
G02X286713Y340792I1558J2084D01*
G03X286684Y340219I264J-301D01*
G02X287298Y338774I-1685J-1569D01*
G03X287980Y338513I399J22D01*
G01X296918Y347452D01*
X299420D01*
X299480Y347523D01*
G02Y344577I1769J-1473D01*
G01X299420Y344648D01*
X298080D01*
X282888Y329457D01*
X282906Y329354D01*
G02X279887Y326335I-2561J-458D01*
G01X279784Y326353D01*
X266801Y313370D01*
G03X267139Y312691I283J-283D01*
G02X268938Y307947I359J-2577D01*
G03Y307281I222J-333D01*
G02Y302947I-1440J-2167D01*
G03Y302281I222J-333D01*
G02Y297947I-1440J-2167D01*
G03Y297281I222J-333D01*
G02X266058I-1440J-2167D01*
G03Y297947I-222J333D01*
G02Y302281I1440J2167D01*
G03Y302947I-222J333D01*
G02Y307281I1440J2167D01*
G03Y307947I-222J333D01*
G02X264921Y310473I1440J2167D01*
G03X264242Y310811I-396J55D01*
G01X255272Y301841D01*
Y293239D01*
X255344Y293179D01*
G02X252398I-1473J-1769D01*
G37*
G36*
G01X374549Y13827D02*
G03X373949I-300J-264D01*
G02X369458Y16110I-1950J1723D01*
G03X369192Y16576I-391J86D01*
G02X368276Y21000I807J2474D01*
G03Y21600I-264J300D01*
G02X371722I1723J1950D01*
G03Y21000I264J-300D01*
G02X372540Y18490I-1723J-1950D01*
G03X372806Y18024I391J-86D01*
G02X373949Y17273I-807J-2474D01*
G03X374549I300J264D01*
G02X378449I1950J-1723D01*
G03X379049I300J264D01*
G02X380136Y18005I1950J-1723D01*
G03X380336Y18604I-133J377D01*
G02X383362Y17595I2163J1446D01*
G03X383162Y16996I133J-377D01*
G02X379049Y13827I-2163J-1446D01*
G03X378449I-300J-264D01*
G02X374549I-1950J1723D01*
G37*
G36*
G01X98982Y38839D02*
G03X99102Y38253I320J-240D01*
G02X95718Y37561I-1302J-2253D01*
G03X95598Y38147I-320J240D01*
G02X95497Y38209I1310J2248D01*
G03X94964Y38115I-215J-337D01*
G02X91644Y41979I-2064J1585D01*
G03X91657Y42671I-194J350D01*
G02X94256Y42621I1343J2229D01*
G03X94243Y41929I194J-350D01*
G02X94303Y41891I-1362J-2217D01*
G03X94836Y41985I215J337D01*
G02X98982Y38839I2064J-1585D01*
G37*
G36*
G01X387850Y70096D02*
X387868Y70199D01*
X372918Y85148D01*
X367328D01*
X367268Y85077D01*
G02Y88023I-1769J1473D01*
G01X367328Y87952D01*
X374080D01*
X389850Y72181D01*
X389953Y72199D01*
G02X392972Y69180I458J-2561D01*
G01X392954Y69077D01*
X395600Y66431D01*
Y46879D01*
X395672Y46819D01*
G02X392726I-1473J-1769D01*
G01X392798Y46879D01*
Y65269D01*
X390972Y67095D01*
X390869Y67077D01*
G02X387850Y70096I-458J2561D01*
G37*
G36*
G01X95586Y52332D02*
G03X96119Y51999I397J43D01*
G02X94412Y49268I880J-2449D01*
G03X93879Y49601I-397J-43D01*
G02X95586Y52332I-880J2449D01*
G37*
G36*
G01X381965Y51248D02*
X381881Y51249D01*
X380881Y50250D01*
X380866Y50209D01*
G02X379211Y53600I-2438J910D01*
G03X379727Y53918I121J382D01*
G02X380354Y55160I2272J-368D01*
G03Y55440I-143J140D01*
G02X382427Y59312I1645J1610D01*
G03X382900Y59684I74J393D01*
G02X385041Y56989I2599J-134D01*
G01X384938Y57007D01*
X384144Y56213D01*
X384128Y56176D01*
G02X383644Y55440I-2130J873D01*
G03Y55160I143J-140D01*
G02X381965Y51248I-1645J-1610D01*
G37*
G36*
G01X343018Y65381D02*
G03Y64779I264J-301D01*
G02X340153Y64918I-1520J-1729D01*
G03Y65242I-117J162D01*
G02X339995Y65367I1348J1866D01*
G03X339717Y65351I-131J-151D01*
G02Y68869I-1918J1759D01*
G03X339995Y68853I147J135D01*
G02X343018Y65381I1504J-1743D01*
G37*
G36*
G01X379549Y63827D02*
G03X378949I-300J-264D01*
G02X375276Y67500I-1950J1723D01*
G03Y68100I-264J300D01*
G02X378949Y71773I1723J1950D01*
G03X379549I300J264D01*
G02X383222Y68100I1950J-1723D01*
G03Y67500I264J-300D01*
G02X379549Y63827I-1723J-1950D01*
G37*
G36*
G01X291779Y70653D02*
G03X291913Y69986I274J-292D01*
G02X289219Y69447I-914J-2436D01*
G03X289085Y70114I-274J292D01*
G02X288658Y70320I912J2437D01*
G01X288611Y70348D01*
X287387D01*
X287340Y70320D01*
G02X285717Y75137I-1341J2230D01*
G03X286050Y75670I-43J397D01*
G02X287097Y78742I2449J880D01*
G03X287231Y79275I-215J337D01*
G02X290901Y78358I2268J1275D01*
G03X290767Y77825I215J-337D01*
G02X290861Y75458I-2268J-1275D01*
G03X291061Y74925I363J-168D01*
G02X291779Y70653I-1062J-2375D01*
G37*
G36*
G01X77191Y68961D02*
G03X76643Y68939I-262J-302D01*
G02X73354Y72160I-1644J1611D01*
G03Y72440I-143J140D01*
G02X76508Y75789I1645J1611D01*
G03X77056Y75811I262J302D01*
G02X80345Y72590I1645J-1611D01*
G03Y72310I143J-140D01*
G02X77191Y68961I-1645J-1611D01*
G37*
G36*
G01X311018Y88156D02*
X311032Y88131D01*
X311986Y87176D01*
X322806D01*
G03X323101Y87846I0J400D01*
G02X322590Y90046I1699J1554D01*
G01X322598Y90073D01*
Y91712D01*
X322570Y91759D01*
G02X327030I2230J1341D01*
G01X327002Y91712D01*
Y90073D01*
X327010Y90046D01*
G02X326499Y87846I-2210J-646D01*
G03X326794Y87176I295J-270D01*
G01X336486D01*
X349411Y74252D01*
X354326D01*
X354353Y74260D01*
G02Y69840I646J-2210D01*
G01X354326Y69848D01*
X347587D01*
X334662Y82774D01*
X310162D01*
X307918Y85017D01*
X307893Y85031D01*
G02X311018Y88156I1106J2019D01*
G37*
G36*
G01X306044Y71687D02*
G03X305445Y71887I-377J-133D01*
G02X306454Y74913I-1446J2163D01*
G03X307053Y74713I377J133D01*
G02X309840Y74780I1446J-2163D01*
G01X309887Y74752D01*
X311111D01*
X311158Y74780D01*
G02Y70320I1341J-2230D01*
G01X311111Y70348D01*
X309887D01*
X309840Y70320D01*
G02X306044Y71687I-1341J2230D01*
G37*
G36*
G01X76188Y82486D02*
G03Y82214I147J-136D01*
G02X72810I-1689J-1564D01*
G03Y82486I-147J136D01*
G02X76188I1689J1564D01*
G37*
G36*
G01X219265Y188379D02*
G02Y192721I-766J2171D01*
G03X219798Y193098I133J377D01*
G01Y196048D01*
X223501Y199752D01*
X282997D01*
X365700Y117048D01*
Y99552D01*
X363497Y97348D01*
X343001D01*
X270001Y170348D01*
X221001D01*
X219798Y171552D01*
Y188002D01*
G03X219265Y188379I-400J0D01*
G37*
G36*
G01X313590Y101146D02*
X313598Y101173D01*
Y102812D01*
X313570Y102859D01*
G02X318030I2230J1341D01*
G01X318002Y102812D01*
Y101173D01*
X318010Y101146D01*
G02X313590I-2210J-646D01*
G37*
G36*
G01X756265Y152610D02*
G03X755733I-266J-299D01*
G02X752276Y156500I-1734J1940D01*
G03Y157100I-264J300D01*
G02X755733Y160990I1723J1950D01*
G03X756265I266J299D01*
G02X759722Y157100I1734J-1940D01*
G03Y156500I264J-300D01*
G02X756265Y152610I-1723J-1950D01*
G37*
G36*
G01X869080Y162249D02*
G03X869091Y161657I274J-291D01*
G02X865996Y161599I-1516J-1733D01*
G03X865985Y162191I-274J291D01*
G02X869080Y162249I1516J1733D01*
G37*
G36*
G01X147170Y163841D02*
X147198Y163888D01*
Y165727D01*
X147190Y165754D01*
G02X151610I2210J646D01*
G01X151602Y165727D01*
Y163888D01*
X151630Y163841D01*
G02X147170I-2230J-1341D01*
G37*
G36*
G01X154292Y165254D02*
X154279Y165308D01*
X153119Y166467D01*
X153094Y166481D01*
G02X156219Y169606I1106J2019D01*
G01X156233Y169581D01*
X157392Y168421D01*
X157446Y168408D01*
G02X154292Y165254I-629J-2525D01*
G37*
G36*
G01X831817Y217500D02*
G03X832359Y217386I330J225D01*
G02X831676Y214132I1217J-1954D01*
G03X831134Y214246I-330J-225D01*
G02X831817Y217500I-1217J1954D01*
G37*
G36*
G01X824402Y261654D02*
Y259388D01*
X824430Y259341D01*
G02X819970I-2230J-1341D01*
G01X819998Y259388D01*
Y260759D01*
X819982Y260797D01*
G02X824119Y262806I2118J903D01*
G01X824133Y262781D01*
X824402Y262512D01*
Y261746D01*
G02Y261654I-2302J-46D01*
G37*
G36*
G01X814270Y271941D02*
X814298Y271988D01*
Y275012D01*
X814667Y275381D01*
X814681Y275406D01*
G02X818726Y273206I2019J-1106D01*
G01X818702Y273162D01*
Y271988D01*
X818730Y271941D01*
G02X814270I-2230J-1341D01*
G37*
G36*
G01X843605Y278905D02*
X843580Y278891D01*
X841987Y277298D01*
X822773D01*
X822746Y277290D01*
G02X821454I-646J2210D01*
G01X821427Y277298D01*
X772137D01*
X749338Y300098D01*
Y312596D01*
X749309Y312643D01*
G02X749607Y315727I2230J1341D01*
G03X749602Y316269I-297J268D01*
G02X752633Y320392I1897J1781D01*
G03X753146Y320538I175J360D01*
G02X757083Y317211I2200J-1390D01*
G03X757103Y316599I267J-298D01*
G02X754321Y312230I-1604J-2049D01*
G03X753740Y311873I-181J-357D01*
G01Y301922D01*
X773961Y281702D01*
X821427D01*
X821454Y281710D01*
G02X822746I646J-2210D01*
G01X822773Y281702D01*
X840163D01*
X840466Y282005D01*
X840480Y282030D01*
G02X843605Y278905I2019J-1106D01*
G37*
G36*
G01X868180Y285825D02*
X868136Y285848D01*
X866172D01*
X866145Y285840D01*
G02Y290260I-646J2210D01*
G01X866172Y290252D01*
X867900D01*
X867950Y290285D01*
G02X868180Y285825I1449J-2161D01*
G37*
G36*
G01X798596Y296621D02*
G03Y296021I264J-300D01*
G02X795150I-1723J-1950D01*
G03Y296621I-264J300D01*
G02Y300521I1723J1950D01*
G03Y301121I-264J300D01*
G02Y305021I1723J1950D01*
G03Y305621I-264J300D01*
G02X798596I1723J1950D01*
G03Y305021I264J-300D01*
G02Y301121I-1723J-1950D01*
G03Y300521I264J-300D01*
G02Y296621I-1723J-1950D01*
G37*
G36*
G01X871481Y292511D02*
X871428Y292548D01*
X869472D01*
X869445Y292540D01*
G02Y296960I-646J2210D01*
G01X869472Y296952D01*
X871835D01*
X871876Y296971D01*
G02X871481Y292511I1123J-2347D01*
G37*
G36*
G01X281721Y297664D02*
G03Y297064I264J-300D01*
G02X278275I-1723J-1950D01*
G03Y297664I-264J300D01*
G02Y301564I1723J1950D01*
G03Y302164I-264J300D01*
G02Y306064I1723J1950D01*
G03Y306664I-264J300D01*
G02X281721I1723J1950D01*
G03Y306064I264J-300D01*
G02Y302164I-1723J-1950D01*
G03Y301564I264J-300D01*
G02Y297664I-1723J-1950D01*
G37*
G36*
G01X865499Y323778D02*
X865545Y323752D01*
X867226D01*
X867253Y323760D01*
G02Y319340I646J-2210D01*
G01X867226Y319348D01*
X865628D01*
X865579Y319318D01*
G02X865499Y323778I-1380J2206D01*
G37*
G36*
G01X556229Y328457D02*
G03X556220Y329051I-272J293D01*
G02X556083Y332840I1713J1959D01*
G03X556105Y333378I-284J281D01*
G02X559949Y333220I1994J1672D01*
G03X559927Y332682I284J-281D01*
G02X559703Y329103I-1994J-1672D01*
G03X559712Y328509I272J-293D01*
G02X559939Y324816I-1713J-1959D01*
G03Y324284I299J-266D01*
G02X556059I-1940J-1734D01*
G03Y324816I-299J266D01*
G02X556229Y328457I1940J1734D01*
G37*
G36*
G01X775017Y326086D02*
G03X775498Y325556I373J-145D01*
G02X774281Y321291I701J-2506D01*
G03X774003Y321307I-147J-135D01*
G02X771069Y324854I-1504J1743D01*
G03X771124Y325427I-249J313D01*
G02X771130Y328428I1749J1497D01*
G03X771114Y328706I-151J131D01*
G02X774632I1759J1918D01*
G03X774616Y328428I135J-147D01*
G02X775017Y326086I-1743J-1504D01*
G37*
G36*
G01X326495Y331752D02*
G03X326095Y331378I-1J-400D01*
G02X323957Y334111I-2596J172D01*
G01X324060Y334093D01*
X324203Y334236D01*
X324211Y334306D01*
G02X324810Y335618I2288J-252D01*
G03Y335890I-147J136D01*
G02X328188I1689J1564D01*
G03Y335618I147J-136D01*
G02X326495Y331752I-1689J-1564D01*
G37*
G36*
G01X793003Y334793D02*
G03X793281Y334809I131J151D01*
G02Y331291I1918J-1759D01*
G03X793003Y331307I-147J-135D01*
G02X789359Y333898I-1504J1743D01*
G03X789137Y334416I-372J147D01*
G02X788256Y338054I862J2134D01*
G03X788240Y338332I-151J131D01*
G02X791758I1759J1918D01*
G03X791742Y338054I135J-147D01*
G02X792139Y335702I-1743J-1504D01*
G03X792361Y335184I372J-147D01*
G02X793003Y334793I-860J-2135D01*
G37*
G36*
G01X871380Y333925D02*
X871336Y333948D01*
X868972D01*
X868945Y333940D01*
G02Y338360I-646J2210D01*
G01X868972Y338352D01*
X871100D01*
X871150Y338385D01*
G02X871380Y333925I1449J-2161D01*
G37*
G36*
G01X292264Y350174D02*
G03X291732I-266J-299D01*
G02X288275Y354064I-1734J1940D01*
G03Y354664I-264J300D01*
G02Y358564I1723J1950D01*
G03Y359164I-264J300D01*
G02X291732Y363054I1723J1950D01*
G03X292264I266J299D01*
G02X295721Y359164I1734J-1940D01*
G03Y358564I264J-300D01*
G02Y354664I-1723J-1950D01*
G03Y354064I264J-300D01*
G02X292264Y350174I-1723J-1950D01*
G37*
G36*
G01X786201Y357974D02*
G03Y357374I264J-300D01*
G02X782755I-1723J-1950D01*
G03Y357974I-264J300D01*
G02X782025Y360793I1723J1950D01*
G03X781626Y361326I-377J134D01*
G02X779528Y362201I-148J2598D01*
G03X778928I-300J-264D01*
G02X775028I-1950J1723D01*
G03X774428I-300J-264D01*
G02X774418Y362190I-1930J1745D01*
G03Y361658I299J-266D01*
G02X770538I-1940J-1734D01*
G03Y362190I-299J266D01*
G02X774428Y365647I1940J1734D01*
G03X775028I300J264D01*
G02X778928I1950J-1723D01*
G03X779528I300J264D01*
G02X783931Y363055I1950J-1723D01*
G03X784330Y362522I377J-134D01*
G02X786201Y357974I148J-2598D01*
G37*
G36*
G01X144283Y423048D02*
G03X143777Y422721I-110J-384D01*
G02X140224Y424967I-2278J329D01*
G03Y425633I-221J333D01*
G02X143268Y429023I1275J1917D01*
G01X143328Y428952D01*
X143580D01*
X144438Y428093D01*
X144541Y428111D01*
G02X144283Y423048I458J-2561D01*
G37*
G36*
G01X133690Y511280D02*
X133737Y511252D01*
X134961D01*
X135008Y511280D01*
G02Y506820I1341J-2230D01*
G01X134961Y506848D01*
X133737D01*
X133690Y506820D01*
G02Y511280I-1341J2230D01*
G37*
G36*
G01X97336Y511711D02*
G03X97064I-136J-147D01*
G02Y515089I-1564J1689D01*
G03X97336I136J147D01*
G02Y511711I1564J-1689D01*
G37*
G36*
G01X61690Y535988D02*
G03Y535716I147J-136D01*
G02X58312Y535712I-1687J-1566D01*
G03Y535984I-147J136D01*
G02X61690Y535988I1687J1566D01*
G37*
G36*
G01X137167Y551566D02*
X137117Y551598D01*
X136088D01*
X136041Y551570D01*
G02Y556030I-1341J2230D01*
G01X136088Y556002D01*
X139028D01*
X139497Y555533D01*
X139522Y555519D01*
G02X137167Y551566I-1106J-2019D01*
G37*
G36*
G01X142633Y564023D02*
G03X142579Y563416I231J-326D01*
G02X139607Y563677I-1639J-1616D01*
G03X139661Y564284I-231J326D01*
G02X139088Y565264I1639J1616D01*
G01X139073Y565313D01*
X136391Y567996D01*
X136343Y568011D01*
G02X139652Y571009I757J2489D01*
G01X139664Y570950D01*
X143502Y567112D01*
Y566573D01*
X143510Y566546D01*
G02X142633Y564023I-2210J-646D01*
G37*
G36*
G01X158379Y575694D02*
X158432Y575655D01*
X158698D01*
Y576115D01*
X158684Y576151D01*
G02X163103Y576679I2140J849D01*
G01X163102Y576665D01*
Y574388D01*
X163130Y574341D01*
G02X158653Y571688I-2230J-1341D01*
G03X158114Y571836I-345J-202D01*
G02X155998Y571779I-1113J2015D01*
G01X155957Y571798D01*
X154388D01*
X154341Y571770D01*
G02Y576230I-1341J2230D01*
G01X154388Y576202D01*
X157217D01*
X157376Y576122D01*
X157404Y576117D01*
G02X158379Y575694I-404J-2266D01*
G37*
G36*
G01X552537Y617750D02*
G03X552563Y618311I-271J294D01*
G02X552776Y622000I1936J1739D01*
G03Y622600I-264J300D01*
G02X556319Y626409I1723J1950D01*
G03X556879I280J286D01*
G02X560517Y622689I1819J-1860D01*
G03X560518Y622115I279J-287D01*
G02X560475Y618334I-1809J-1870D01*
G03X560447Y617775I271J-294D01*
G02X556774Y614102I-1948J-1725D01*
G03X556215Y614074I-265J-299D01*
G02X552537Y617750I-1911J1766D01*
G37*
G36*
G01X127188Y637386D02*
G03Y637114I147J-136D01*
G02X123810I-1689J-1564D01*
G03Y637386I-147J136D01*
G02X127188I1689J1564D01*
G37*
G36*
G01X145885Y647523D02*
G03Y646964I286J-279D01*
G02X142591I-1647J-1608D01*
G03Y647523I-286J280D01*
G02X145885I1647J1608D01*
G37*
G36*
G01X818666Y665549D02*
X818698Y665599D01*
Y666612D01*
X818670Y666659D01*
G02X823130I2230J1341D01*
G01X823102Y666612D01*
Y663688D01*
X822633Y663219D01*
X822619Y663194D01*
G02X818666Y665549I-2019J1106D01*
G37*
G36*
G01X811323Y674568D02*
G02X810598Y676200I1477J1633D01*
G01Y678512D01*
X810570Y678559D01*
G02X815030I2230J1341D01*
G01X815002Y678512D01*
Y677335D01*
X815042Y677281D01*
G02X811323Y674568I-1842J-1381D01*
G37*
G36*
G01X808462Y699826D02*
G03X808485Y699186I251J-311D01*
G02X805368Y699077I-1486J-2136D01*
G03X805345Y699717I-251J311D01*
G02X805391Y704020I1486J2136D01*
G03Y704686I-222J333D01*
G02Y709020I1440J2167D01*
G03Y709686I-222J333D01*
G02X808271I1440J2167D01*
G03Y709020I222J-333D01*
G02Y704686I-1440J-2167D01*
G03Y704020I222J-333D01*
G02X808462Y699826I-1440J-2167D01*
G37*
G36*
G01X287623Y745937D02*
G03X288275Y745808I369J154D01*
G01X297418Y754952D01*
X306918D01*
X307216Y755249D01*
X307018Y755447D01*
X306938Y755449D01*
G02X309320Y759226I61J2601D01*
G03X309873Y759058I357J181D01*
G02X310790Y754757I1126J-2008D01*
G01X310697Y754766D01*
X308080Y752148D01*
X298580D01*
X286600Y740169D01*
X286723Y740028D01*
G02X284306Y735754I-1959J-1713D01*
G01X284203Y735772D01*
X280003Y731572D01*
G03X280235Y730893I283J-282D01*
G02X277656Y728314I-296J-2283D01*
G03X276977Y728546I-397J-51D01*
G01X268265Y719834D01*
G03X268542Y719152I283J-282D01*
G02X269939Y714383I-43J-2602D01*
G03Y713717I222J-333D01*
G02Y709383I-1440J-2167D01*
G03Y708717I222J-333D01*
G02Y704383I-1440J-2167D01*
G03Y703717I222J-333D01*
G02X267059I-1440J-2167D01*
G03Y704383I-222J333D01*
G02Y708717I1440J2167D01*
G03Y709383I-222J333D01*
G02Y713717I1440J2167D01*
G03Y714383I-222J333D01*
G02X265897Y716507I1440J2167D01*
G03X265215Y716784I-400J-6D01*
G01X255900Y707469D01*
Y699529D01*
X255972Y699469D01*
G02X253026I-1473J-1769D01*
G01X253098Y699529D01*
Y708631D01*
X282221Y737754D01*
X282203Y737857D01*
G02X283277Y740450I2561J458D01*
G01X283362Y740510D01*
Y740896D01*
X284741Y742274D01*
G03X284612Y742926I-283J283D01*
G02X283935Y743361I887J2124D01*
G03X283663I-136J-147D01*
G02X282507Y747316I-1564J1689D01*
G03X282936Y747888I71J393D01*
G02X287128Y747235I2328J1162D01*
G03X287131Y746673I286J-279D01*
G02X287623Y745937I-1632J-1623D01*
G37*
G36*
G01X796054Y700903D02*
G03Y700303I264J-300D01*
G02X792608I-1723J-1950D01*
G03Y700903I-264J300D01*
G02Y704803I1723J1950D01*
G03Y705403I-264J300D01*
G02Y709303I1723J1950D01*
G03Y709903I-264J300D01*
G02X796054I1723J1950D01*
G03Y709303I264J-300D01*
G02Y705403I-1723J-1950D01*
G03Y704803I264J-300D01*
G02Y700903I-1723J-1950D01*
G37*
G36*
G01X282939Y703816D02*
G03Y703284I299J-266D01*
G02X279059I-1940J-1734D01*
G03Y703816I-299J266D01*
G02X282939I1940J1734D01*
G37*
G36*
G01X282675Y715559D02*
G03X282599Y715032I257J-306D01*
G02X278757Y715581I-2166J-1442D01*
G03X278833Y716108I-257J306D01*
G02X282675Y715559I2166J1442D01*
G37*
G36*
G01X747737Y714135D02*
G03X747138Y714068I-270J-295D01*
G02X743517Y717689I-2139J1482D01*
G03X743584Y718288I-228J329D01*
G02X747449Y721773I1915J1762D01*
G03X748049I300J264D01*
G02X751696Y718077I1949J-1724D01*
G03X751629Y717544I261J-303D01*
G02X747737Y714135I-2130J-1494D01*
G37*
G36*
G01X772822Y724894D02*
G03X772807Y724339I281J-285D01*
G02X769323Y724246I-1702J-1550D01*
G03X769278Y724799I-310J253D01*
G02X772822Y724894I1721J1951D01*
G37*
G36*
G01X867840Y726780D02*
X867887Y726752D01*
X869111D01*
X869158Y726780D01*
G02Y722320I1341J-2230D01*
G01X869111Y722348D01*
X867887D01*
X867840Y722320D01*
G02Y726780I-1341J2230D01*
G37*
G36*
G01X793742Y731546D02*
G03X793758Y731268I151J-131D01*
G02X790240I-1759J-1918D01*
G03X790256Y731546I-135J147D01*
G02X789713Y733320I1743J1504D01*
G03X789269Y733764I-397J47D01*
G02X786812Y735330I-270J2286D01*
G03X786566Y735459I-190J-63D01*
G02X788299Y738762I-740J2495D01*
G01X788314Y738717D01*
X788697Y738334D01*
X788790Y738343D01*
G02X791285Y735780I209J-2293D01*
G03X791729Y735336I397J-47D01*
G02X793742Y731546I270J-2286D01*
G37*
G36*
G01X771615Y734690D02*
G03X772202Y734718I281J285D01*
G02Y731382I1997J-1668D01*
G03X771615Y731410I-306J-257D01*
G02Y734690I-1616J1640D01*
G37*
G36*
G01X326247Y742043D02*
G03X326227Y742323I-152J130D01*
G02X329865Y744956I1522J1727D01*
G03X330370Y744738I368J158D01*
G02X330805Y739733I893J-2444D01*
G01X330702Y739751D01*
X330100Y739148D01*
X329828D01*
X329768Y739077D01*
G02X326247Y742043I-1769J1473D01*
G37*
G36*
G01X784919Y758432D02*
G03Y757832I264J-300D01*
G02X781473I-1723J-1950D01*
G03Y758432I-264J300D01*
G02X780743Y761251I1723J1950D01*
G03X780344Y761784I-377J134D01*
G02X778246Y762659I-148J2598D01*
G03X777646I-300J-264D01*
G02X773746I-1950J1723D01*
G03X773146I-300J-264D01*
G02X773136Y762648I-1930J1745D01*
G03Y762116I299J-266D01*
G02X769256I-1940J-1734D01*
G03Y762648I-299J266D01*
G02X773146Y766105I1940J1734D01*
G03X773746I300J264D01*
G02X777646I1950J-1723D01*
G03X778246I300J264D01*
G02X782649Y763513I1950J-1723D01*
G03X783048Y762980I377J-134D01*
G02X784919Y758432I148J-2598D01*
G37*
G36*
G01X797155Y758777D02*
X797184Y758824D01*
Y760048D01*
X797155Y760095D01*
G02X801615I2230J1341D01*
G01X801586Y760048D01*
Y758824D01*
X801615Y758777D01*
G02X797155I-2230J-1341D01*
G37*
G36*
G01X293265Y756110D02*
G03X292733I-266J-299D01*
G02X289276Y760000I-1734J1940D01*
G03Y760600I-264J300D01*
G02Y764500I1723J1950D01*
G03Y765100I-264J300D01*
G02X292733Y768990I1723J1950D01*
G03X293265I266J299D01*
G02X296722Y765100I1734J-1940D01*
G03Y764500I264J-300D01*
G02Y760600I-1723J-1950D01*
G03Y760000I264J-300D01*
G02X293265Y756110I-1723J-1950D01*
G37*
G36*
G01X207114Y836257D02*
G03X206534I-290J-276D01*
G02X202733Y839811I-1885J1793D01*
G03Y840352I-294J271D01*
G02X202644Y843771I1916J1761D01*
G03X202624Y844304I-308J255D01*
G02X206447Y847832I1872J1807D01*
G03X207047Y847833I300J265D01*
G02X210934Y844373I1953J-1720D01*
G03X210932Y843840I298J-268D01*
G02X210907Y840358I-1946J-1727D01*
G03X210909Y839817I296J-269D01*
G02X207114Y836257I-1910J-1767D01*
G37*
G36*
G01X217696Y885577D02*
G03X217629Y885044I261J-303D01*
G02X213802Y885523I-2130J-1494D01*
G03X213869Y886056I-261J303D01*
G02X217949Y889273I2130J1494D01*
G03X218549I300J264D01*
G02Y885827I1950J-1723D01*
G03X217949I-300J-264D01*
G02X217696Y885577I-1951J1722D01*
G37*
G36*
G01X213619Y895944D02*
G03X214151Y895835I325J233D01*
G02X213365Y892123I1349J-2225D01*
G01X213305Y892208D01*
X212159D01*
X212052Y892316D01*
X211959Y892307D01*
G02X213619Y895944I-209J2293D01*
G37*
G36*
G01X217549Y924890D02*
G03X216949I-300J-264D01*
G02Y928336I-1950J1723D01*
G03X217549I300J264D01*
G02Y924890I1950J-1723D01*
G37*
G36*
G01Y937890D02*
G03X216949I-300J-264D01*
G02X213276Y941563I-1950J1723D01*
G03Y942163I-264J300D01*
G02Y946063I1723J1950D01*
G03Y946663I-264J300D01*
G02X216949Y950336I1723J1950D01*
G03X217549I300J264D01*
G02X221062Y946533I1950J-1723D01*
G03Y945893I240J-320D01*
G02X221358Y941993I-1563J-2080D01*
G03Y941433I286J-280D01*
G02X217549Y937890I-1859J-1820D01*
G37*
G36*
G01X239790Y1066646D02*
X239798Y1066673D01*
Y1068312D01*
X239770Y1068359D01*
G02X244230I2230J1341D01*
G01X244202Y1068312D01*
Y1066673D01*
X244210Y1066646D01*
G02X239790I-2210J-646D01*
G37*
G36*
G01X823781Y1071194D02*
X823767Y1071219D01*
X823298Y1071688D01*
Y1074912D01*
X823270Y1074959D01*
G02X827730I2230J1341D01*
G01X827702Y1074912D01*
Y1073599D01*
X827734Y1073549D01*
G02X823781Y1071194I-1934J-1249D01*
G37*
G36*
G01X227590Y1074246D02*
X227598Y1074273D01*
Y1075912D01*
X227570Y1075959D01*
G02X232030I2230J1341D01*
G01X232002Y1075912D01*
Y1074273D01*
X232010Y1074246D01*
G02X227590I-2210J-646D01*
G37*
G36*
G01X813190Y1079446D02*
X813198Y1079473D01*
Y1081112D01*
X813170Y1081159D01*
G02X817630I2230J1341D01*
G01X817602Y1081112D01*
Y1079473D01*
X817610Y1079446D01*
G02X813190I-2210J-646D01*
G37*
G36*
G01X808507Y1108890D02*
G03X808462Y1108202I180J-357D01*
G02X808679Y1104063I-1463J-2152D01*
G03X808725Y1103419I259J-305D01*
G02X809281Y1099481I-1384J-2204D01*
G03X809302Y1098926I298J-267D01*
G02X809356Y1098872I-1812J-1867D01*
G03X809642I143J140D01*
G02X809765Y1095110I1857J-1822D01*
G03X809233I-266J-299D01*
G02X805186Y1095858I-1734J1940D01*
G03X804520Y1095927I-356J-183D01*
G02X800765Y1095626I-2021J1639D01*
G03X800233I-266J-299D01*
G02Y1099506I-1734J1940D01*
G03X800765I266J299D01*
G02X804812Y1098758I1734J-1940D01*
G03X805478Y1098689I356J183D01*
G02X805559Y1098785I2029J-1630D01*
G03X805538Y1099340I-298J267D01*
G02X805661Y1103203I1803J1876D01*
G03X805615Y1103847I-259J305D01*
G02X805833Y1108376I1384J2203D01*
G03X805878Y1109064I-180J357D01*
G02X805901Y1113383I1463J2152D01*
G03Y1114049I-222J333D01*
G02X808781I1440J2167D01*
G03Y1113383I222J-333D01*
G02X808507Y1108890I-1440J-2167D01*
G37*
G36*
G01X770111Y1126195D02*
G03X770390Y1126196I139J144D01*
G02X770605Y1122718I1609J-1646D01*
G03X770329Y1122684I-120J-159D01*
G02X770111Y1126195I-2023J1637D01*
G37*
G36*
G01X867432Y1126534D02*
X867397Y1126548D01*
X865172D01*
X865145Y1126540D01*
G02Y1130960I-646J2210D01*
G01X865172Y1130952D01*
X866735D01*
X866789Y1130994D01*
G02X867432Y1126534I1610J-2044D01*
G37*
G36*
G01X781686Y1131770D02*
G03X781932Y1131641I190J63D01*
G02X780199Y1128338I740J-2495D01*
G01X780184Y1128383D01*
X779801Y1128766D01*
X779708Y1128757D01*
G02X781686Y1131770I-209J2293D01*
G37*
G36*
G01X771765Y1132232D02*
G03X771893Y1132480I-63J190D01*
G02X775236Y1130777I2490J755D01*
G01X775193Y1130762D01*
X774783Y1130352D01*
X774792Y1130259D01*
G02X771765Y1132232I-2293J-209D01*
G37*
G36*
G01X793936Y1134167D02*
G03X793658Y1134183I-147J-135D01*
G02X789878Y1135584I-1504J1743D01*
G03X789665Y1135754I-198J-30D01*
G02X787432Y1139063I-166J2296D01*
G01X787452Y1139105D01*
Y1140431D01*
X787367Y1140491D01*
G02X790588Y1140686I1487J2135D01*
G03X790654Y1140041I266J-299D01*
G02X791775Y1138392I-1155J-1991D01*
G03X791988Y1138222I198J30D01*
G02X793658Y1137669I166J-2296D01*
G03X793936Y1137685I131J151D01*
G02Y1134167I1918J-1759D01*
G37*
G36*
G01X262294Y1151085D02*
G03X261761Y1151077I-262J-302D01*
G02X261704Y1154957I-1762J1915D01*
G03X262237Y1154965I262J302D01*
G02X265949Y1154773I1762J-1915D01*
G03X266549I300J264D01*
G02X270233Y1154990I1950J-1723D01*
G03X270765I266J299D01*
G02Y1151110I1734J-1940D01*
G03X270233I-266J-299D01*
G02X266549Y1151327I-1734J1940D01*
G03X265949I-300J-264D01*
G02X262294Y1151085I-1950J1723D01*
G37*
G36*
G01X785056Y1159942D02*
G03Y1159342I264J-300D01*
G02X781610I-1723J-1950D01*
G03Y1159942I-264J300D01*
G02X780880Y1162761I1723J1950D01*
G03X780481Y1163294I-377J134D01*
G02X778383Y1164169I-148J2598D01*
G03X777783I-300J-264D01*
G02X773883I-1950J1723D01*
G03X773283I-300J-264D01*
G02X773273Y1164158I-1930J1745D01*
G03Y1163626I299J-266D01*
G02X769393I-1940J-1734D01*
G03Y1164158I-299J266D01*
G02X773283Y1167615I1940J1734D01*
G03X773883I300J264D01*
G02X777783I1950J-1723D01*
G03X778383I300J264D01*
G02X782786Y1165023I1950J-1723D01*
G03X783185Y1164490I377J-134D01*
G02X785056Y1159942I148J-2598D01*
G37*
G36*
G01X261765Y1159610D02*
G03X261233I-266J-299D01*
G02Y1163490I-1734J1940D01*
G03X261765I266J299D01*
G02X265449Y1163273I1734J-1940D01*
G03X266049I300J264D01*
G02X269733Y1163490I1950J-1723D01*
G03X270265I266J299D01*
G02Y1159610I1734J-1940D01*
G03X269733I-266J-299D01*
G02X266049Y1159827I-1734J1940D01*
G03X265449I-300J-264D01*
G02X261765Y1159610I-1950J1723D01*
G37*
G36*
G01X178770Y1362341D02*
X178798Y1362388D01*
Y1364827D01*
X178790Y1364854D01*
G02X179476Y1367225I2210J645D01*
G03X179402Y1367877I-265J300D01*
G02X178481Y1368794I1098J2023D01*
G01X178467Y1368819D01*
X178198Y1369088D01*
Y1369854D01*
G02Y1369946I2302J46D01*
G01Y1372612D01*
X178170Y1372659D01*
G02X182630I2230J1341D01*
G01X182602Y1372612D01*
Y1370841D01*
X182618Y1370803D01*
G02X182024Y1368175I-2118J-902D01*
G03X182098Y1367523I265J-300D01*
G02X183210Y1364854I-1098J-2024D01*
G01X183202Y1364827D01*
Y1362388D01*
X183230Y1362341D01*
G02X178770I-2230J-1341D01*
G37*
G36*
G01X263263Y1501286D02*
X196200Y1434224D01*
Y1388530D01*
X196301Y1388473D01*
G02X194700Y1382498I-1601J-2773D01*
G01X194151D01*
G02X191887Y1383436I0J3201D01*
G01X189798Y1385526D01*
Y1436876D01*
X232204Y1479283D01*
G03X232185Y1479867I-282J283D01*
G02X235433Y1483115I1515J1733D01*
G03X236017Y1483096I301J263D01*
G01X258735Y1505814D01*
G02X263263Y1501286I2264J-2264D01*
G37*
G36*
G01X863991Y1497904D02*
X863978Y1497958D01*
X862809Y1499127D01*
X862774Y1499142D01*
G02X864345Y1503460I924J2109D01*
G01X864372Y1503452D01*
X864711D01*
X865044Y1503118D01*
X865057Y1503109D01*
G02X865558Y1502608I-1358J-1859D01*
G01X865567Y1502595D01*
X867091Y1501071D01*
X867145Y1501058D01*
G02X863991Y1497904I-629J-2525D01*
G37*
G36*
G01X810685Y1506555D02*
G03Y1505889I222J-333D01*
G02X807805I-1440J-2167D01*
G03Y1506555I-222J333D01*
G02X807597Y1510736I1440J2167D01*
G03X807565Y1511379I-253J310D01*
G02X807790Y1515854I1434J2171D01*
G03X807823Y1516543I-186J354D01*
G02X810454Y1516418I1422J2179D01*
G03X810421Y1515729I186J-354D01*
G02X810647Y1511536I-1422J-2179D01*
G03X810679Y1510893I253J-310D01*
G02X810685Y1506555I-1434J-2171D01*
G37*
G36*
G01X797439Y1507383D02*
G03Y1506717I222J-333D01*
G02X794559I-1440J-2167D01*
G03Y1507383I-222J333D01*
G02X794276Y1511500I1440J2167D01*
G03Y1512100I-264J300D01*
G02Y1516000I1723J1950D01*
G03Y1516600I-264J300D01*
G02X797722I1723J1950D01*
G03Y1516000I264J-300D01*
G02Y1512100I-1723J-1950D01*
G03Y1511500I264J-300D01*
G02X797439Y1507383I-1723J-1950D01*
G37*
G36*
G01X290869Y1549023D02*
X290972Y1549005D01*
X309098Y1567131D01*
Y1567804D01*
X309006Y1567863D01*
G02X308859Y1567965I1238J1941D01*
G03X308268Y1567842I-242J-318D01*
G02X307753Y1571035I-2270J1272D01*
G03X308352Y1571104I269J296D01*
G02X311952Y1568252I1897J-1304D01*
G01X311900Y1568194D01*
Y1565969D01*
X292954Y1547023D01*
X292972Y1546920D01*
G02X289953Y1543901I-2561J-458D01*
G01X289850Y1543919D01*
X283900Y1537969D01*
Y1522294D01*
X279869Y1518263D01*
G03X280065Y1517590I283J-283D01*
G02X281222Y1513100I-566J-2540D01*
G03Y1512500I264J-300D01*
G02X277776I-1723J-1950D01*
G03Y1513100I-264J300D01*
G02X276959Y1514484I1723J1950D01*
G03X276286Y1514680I-390J-87D01*
G01X276255Y1514648D01*
X269474D01*
G03X269144Y1514022I0J-400D01*
G02X264854I-2145J-1472D01*
G03X264524Y1514648I-330J226D01*
G01X263828D01*
X263768Y1514577D01*
G02Y1517523I-1769J1473D01*
G01X263828Y1517452D01*
X264362D01*
G03X264760Y1517891I0J400D01*
G02X265579Y1520057I2589J259D01*
G03Y1520643I-273J293D01*
G02X265688Y1524553I1770J1907D01*
G03Y1525169I-255J308D01*
G02X269010I1661J2003D01*
G03Y1524553I255J-308D01*
G02X269119Y1520643I-1661J-2003D01*
G03Y1520057I273J-293D01*
G02X269938Y1517891I-1770J-1907D01*
G03X270336Y1517452I398J-39D01*
G01X275093D01*
X281098Y1523456D01*
Y1524029D01*
X280824D01*
X280767Y1523981D01*
G02X276930Y1527430I-1692J1977D01*
G03X276863Y1527959I-329J227D01*
G02X280414Y1531758I1704J1967D01*
G03X281098Y1532040I284J282D01*
G01Y1539131D01*
X287868Y1545901D01*
X287850Y1546004D01*
G02X290869Y1549023I2561J458D01*
G37*
G36*
G01X392688Y1516234D02*
G03Y1515962I147J-136D01*
G02X389310I-1689J-1564D01*
G03Y1516234I-147J136D01*
G02X392688I1689J1564D01*
G37*
G36*
G01X752940Y1519266D02*
G03Y1518734I299J-266D01*
G02X749060I-1940J-1734D01*
G03Y1519266I-299J266D01*
G02Y1522734I1940J1734D01*
G03Y1523266I-299J266D01*
G02X752940I1940J1734D01*
G03Y1522734I299J-266D01*
G02Y1519266I-1940J-1734D01*
G37*
G36*
G01X772783Y1528268D02*
G03X772799Y1528546I-135J147D01*
G02X772898Y1531661I1743J1504D01*
G03X772903Y1532216I-286J280D01*
G02X772799Y1535258I1674J1580D01*
G03X772776Y1535536I-155J127D01*
G02X776292Y1535620I1712J1959D01*
G03X776283Y1535342I139J-144D01*
G02X776221Y1532185I-1706J-1546D01*
G03X776216Y1531630I286J-280D01*
G02X776285Y1528546I-1674J-1580D01*
G03X776301Y1528268I151J-131D01*
G02X772783I-1759J-1918D01*
G37*
G36*
G01X868305Y1533131D02*
X868280Y1533117D01*
X867396Y1532234D01*
X867399Y1532146D01*
G02X862569Y1533391I-2600J-96D01*
G01X862598Y1533438D01*
Y1533662D01*
X865166Y1536231D01*
X865180Y1536256D01*
G02X868305Y1533131I2019J-1106D01*
G37*
G36*
G01X795781Y1539291D02*
G03X795503Y1539307I-147J-135D01*
G02X791697Y1541048I-1504J1743D01*
G03X791497Y1541248I-200J0D01*
G02X789995Y1541807I2J2302D01*
G03X789717Y1541791I-131J-151D01*
G02Y1545309I-1918J1759D01*
G03X789995Y1545293I147J135D01*
G02X793801Y1543552I1504J-1743D01*
G03X794001Y1543352I200J0D01*
G02X795503Y1542793I-2J-2302D01*
G03X795781Y1542809I131J151D01*
G02Y1539291I1918J-1759D01*
G37*
G36*
G01X863209Y1545003D02*
X863263Y1545016D01*
X863269Y1545022D01*
X863294D01*
X863314Y1545027D01*
G02X864362I524J-2549D01*
G01X864382Y1545022D01*
X866850D01*
X866877Y1545031D01*
G02Y1540611I646J-2210D01*
G01X866850Y1540620D01*
X865661D01*
X865603Y1540566D01*
G02X863209Y1545003I-1765J1912D01*
G37*
G36*
G01X281889Y1554405D02*
G03X281609I-140J-143D01*
G02Y1557695I-1610J1645D01*
G03X281889I140J143D01*
G02X284148Y1558259I1611J-1645D01*
G03X284394Y1558389I56J192D01*
G02X285940Y1555151I2474J-807D01*
G01X285819Y1555197D01*
X285450Y1554828D01*
X285438Y1554810D01*
G02X281889Y1554405I-1939J1240D01*
G37*
G36*
G01X787550Y1563846D02*
G03Y1563246I264J-300D01*
G02X784104I-1723J-1950D01*
G03Y1563846I-264J300D01*
G02X783374Y1566665I1723J1950D01*
G03X782975Y1567198I-377J134D01*
G02X780877Y1568073I-148J2598D01*
G03X780277I-300J-264D01*
G02X776377I-1950J1723D01*
G03X775777I-300J-264D01*
G02X775524Y1567823I-1951J1722D01*
G03X775457Y1567290I261J-303D01*
G02X771630Y1567769I-2130J-1494D01*
G03X771697Y1568302I-261J303D01*
G02X775777Y1571519I2130J1494D01*
G03X776377I300J264D01*
G02X780277I1950J-1723D01*
G03X780877I300J264D01*
G02X785280Y1568927I1950J-1723D01*
G03X785679Y1568394I377J-134D01*
G02X787550Y1563846I148J-2598D01*
G37*
G36*
G01X292264Y1567174D02*
G03X291732I-266J-299D01*
G02X288275Y1571064I-1734J1940D01*
G03Y1571664I-264J300D01*
G02Y1575564I1723J1950D01*
G03Y1576164I-264J300D01*
G02X291732Y1580054I1723J1950D01*
G03X292264I266J299D01*
G02X295721Y1576164I1734J-1940D01*
G03Y1575564I264J-300D01*
G02Y1571664I-1723J-1950D01*
G03Y1571064I264J-300D01*
G02X292264Y1567174I-1723J-1950D01*
G37*
G36*
G01X159874Y1596221D02*
G03X159650Y1596065I-28J-198D01*
G02X157726Y1598829I-2250J485D01*
G03X157950Y1598985I28J198D01*
G02X159874Y1596221I2250J-485D01*
G37*
G36*
G01X197315Y1621743D02*
G03X197328Y1621130I263J-301D01*
G02X193985Y1621057I-1628J-2030D01*
G03X193972Y1621670I-263J301D01*
G02X197315Y1621743I1628J2030D01*
G37*
G36*
G01X181869Y1629104D02*
G03X181944Y1628566I328J-228D01*
G02X178163Y1628036I-1645J-2016D01*
G03X178088Y1628574I-328J228D01*
G02X178057Y1632581I1645J2016D01*
G03X178133Y1633108I-257J306D01*
G02X181975Y1632559I2166J1442D01*
G03X181899Y1632032I257J-306D01*
G02X181869Y1629104I-2166J-1442D01*
G37*
G36*
G01X170943Y1684420D02*
G03X170983Y1684141I160J-119D01*
G02X167757Y1683680I-1383J-1841D01*
G03X167717Y1683959I-160J119D01*
G02X170943Y1684420I1383J1841D01*
G37*
G36*
G01X353622Y1712749D02*
X353711Y1712744D01*
X362918Y1721952D01*
X525918D01*
X740418Y1936452D01*
X753804D01*
X753864Y1936537D01*
G02X758134I2135J-1487D01*
G01X758194Y1936452D01*
X769191D01*
X769199Y1936643D01*
G02X769854Y1938160I2300J-93D01*
G03Y1938440I-143J140D01*
G02X769275Y1940645I1645J1610D01*
G03X768889Y1941148I-386J103D01*
G01X758694D01*
X758634Y1941063D01*
G02X754364I-2135J1487D01*
G01X754304Y1941148D01*
X733555D01*
X526055Y1733648D01*
X387328D01*
X387268Y1733577D01*
G02Y1736523I-1769J1473D01*
G01X387328Y1736452D01*
X524893D01*
X732393Y1943952D01*
X754304D01*
X754364Y1944037D01*
G02X758634I2135J-1487D01*
G01X758694Y1943952D01*
X793580D01*
X794197Y1943334D01*
X794290Y1943343D01*
G02X792199Y1940957I209J-2293D01*
G01X792191Y1941148D01*
X778119D01*
G03X777730Y1940655I0J-400D01*
G02X774253Y1937626I-2531J-605D01*
G03X773722Y1937149I-145J-373D01*
G02X771290Y1934257I-2223J-599D01*
G01X771197Y1934266D01*
X770580Y1933648D01*
X758194D01*
X758134Y1933563D01*
G02X753864I-2135J1487D01*
G01X753804Y1933648D01*
X741580D01*
X527080Y1719148D01*
X364080D01*
X355770Y1710839D01*
X355782Y1710742D01*
G02X353622Y1712749I-2283J-292D01*
G37*
G36*
G01X893146Y1711692D02*
X893092Y1711679D01*
X891833Y1710419D01*
X891819Y1710394D01*
G02X888694Y1713519I-2019J1106D01*
G01X888719Y1713533D01*
X889979Y1714792D01*
X889992Y1714846D01*
G02X893146Y1711692I2525J-629D01*
G37*
G36*
G01X862610Y1715843D02*
X862623Y1715789D01*
X863528Y1714884D01*
X863571Y1714869D01*
G02X862154Y1710490I-771J-2169D01*
G01X862127Y1710498D01*
X861687D01*
X859510Y1712676D01*
X859456Y1712689D01*
G02X862610Y1715843I629J2525D01*
G37*
G36*
G01X169684Y1715526D02*
G03X170350Y1715517I336J217D01*
G02X170314Y1712637I2149J-1467D01*
G03X169648Y1712646I-336J-217D01*
G02X165332Y1712673I-2149J1467D01*
G03X164666I-333J-222D01*
G02Y1715553I-2167J1440D01*
G03X165332I333J222D01*
G02X169684Y1715526I2167J-1440D01*
G37*
G36*
G01X884746Y1719159D02*
X884798Y1719217D01*
Y1720012D01*
X884770Y1720059D01*
G02X889230I2230J1341D01*
G01X889202Y1720012D01*
Y1717249D01*
X888472Y1716519D01*
X888458Y1716494D01*
G02X884746Y1719159I-2019J1105D01*
G37*
G36*
G01X166049Y1724890D02*
G03X165449I-300J-264D01*
G02X162813Y1729123I-1950J1723D01*
G03X163079Y1729656I-106J386D01*
G02X167542Y1732225I2420J958D01*
G03X168208Y1732283I314J248D01*
G02X172755Y1729753I2291J-1233D01*
G03X173021Y1729162I347J-199D01*
G02X170549Y1724890I-522J-2549D01*
G03X169949I-300J-264D01*
G02X166049I-1950J1723D01*
G37*
G36*
G01X871631Y1732828D02*
X871616Y1732870D01*
X870708Y1733779D01*
X870654Y1733792D01*
G02X873808Y1736946I629J2525D01*
G01X873821Y1736892D01*
X876002Y1734712D01*
Y1734273D01*
X876010Y1734246D01*
G02X871631Y1732828I-2210J-646D01*
G37*
G36*
G01X884696Y1739970D02*
G03X885255Y1739916I307J256D01*
G02X884904Y1736230I1645J-2016D01*
G03X884345Y1736284I-307J-256D01*
G02X884696Y1739970I-1645J2016D01*
G37*
G36*
G01X287915Y1865484D02*
X249795Y1827364D01*
X249813Y1827261D01*
G02X246794Y1824242I-2561J-458D01*
G01X246691Y1824260D01*
X203783Y1781352D01*
X203792Y1781259D01*
G02X201708Y1783343I-2293J-209D01*
G01X201801Y1783334D01*
X244709Y1826242D01*
X244691Y1826345D01*
G02X247710Y1829364I2561J458D01*
G01X247813Y1829346D01*
X286998Y1868531D01*
Y1880921D01*
G03X286253Y1881125I-400J1D01*
G02Y1898367I-14596J8621D01*
G03X286998Y1898571I345J203D01*
G01Y1926569D01*
X285801Y1927766D01*
X285708Y1927757D01*
G02X284894Y1927829I-207J2293D01*
G03X284418Y1927590I-104J-386D01*
G02X283439Y1926383I-2418J961D01*
G03Y1925717I222J-333D01*
G02Y1921383I-1440J-2167D01*
G03Y1920717I222J-333D01*
G02X280559I-1440J-2167D01*
G03Y1921383I-222J333D01*
G02Y1925717I1440J2167D01*
G03Y1926383I-222J333D01*
G02X282972Y1930963I1441J2167D01*
G03X283474Y1931144I150J371D01*
G02X287792Y1929841I2025J-1094D01*
G01X287783Y1929748D01*
X287915Y1929616D01*
G03X288597Y1929899I282J283D01*
G01X288598Y1945736D01*
X288422Y1945758D01*
G02X287286Y1946233I288J2284D01*
G03X286736Y1946181I-248J-314D01*
G02X286422Y1949500I-1737J1510D01*
G03X286972Y1949552I248J314D01*
G02X291002Y1947833I1737J-1510D01*
G01X290993Y1947740D01*
X291400Y1947333D01*
Y1935094D01*
G03X292093Y1934822I400J0D01*
G02X296138Y1934532I1906J-1772D01*
G03X296737Y1934465I329J228D01*
G02X300233Y1934490I1762J-1915D01*
G03X300765I266J299D01*
G02X304449Y1934273I1734J-1940D01*
G03X305049I300J264D01*
G02Y1930827I1950J-1723D01*
G03X304449I-300J-264D01*
G02X300765Y1930610I-1950J1723D01*
G03X300233I-266J-299D01*
G02X296360Y1931068I-1734J1940D01*
G03X295761Y1931135I-329J-228D01*
G02X292093Y1931278I-1762J1915D01*
G03X291400Y1931006I-293J-272D01*
G01Y1821131D01*
X299434Y1813097D01*
X299537Y1813115D01*
G02X302556Y1810096I458J-2561D01*
G01X302538Y1809993D01*
X348197Y1764334D01*
X348290Y1764343D01*
G02X346206Y1762259I209J-2293D01*
G01X346215Y1762352D01*
X300556Y1808011D01*
X300453Y1807993D01*
G02X297434Y1811012I-458J2561D01*
G01X297452Y1811115D01*
X288598Y1819969D01*
Y1865201D01*
G03X287915Y1865484I-400J0D01*
G37*
G36*
G01X878173Y1783967D02*
G03X878179Y1784572I-259J305D01*
G02X881191Y1784546I1521J1728D01*
G03X881185Y1783941I259J-305D01*
G02X878173Y1783967I-1521J-1728D01*
G37*
G36*
G01X796058Y1807793D02*
X796151Y1807784D01*
X799098Y1810731D01*
Y1820288D01*
X801216Y1822406D01*
X801207Y1822499D01*
G02X805299Y1824144I2293J209D01*
G03X805579Y1824111I157J124D01*
G02X806791Y1820007I1421J-1811D01*
G01X806698Y1820016D01*
X803800Y1817118D01*
Y1808781D01*
X797118Y1802098D01*
X794829D01*
X794769Y1802027D01*
G02X791231I-1769J1473D01*
G01X791171Y1802098D01*
X759619D01*
X741010Y1820708D01*
X713481D01*
X713421Y1820636D01*
G02X710056Y1823768I-1769J1473D01*
G03X710072Y1824040I-138J145D01*
G02X713617Y1826977I1776J1464D01*
G01X713677Y1826906D01*
X741465D01*
X761469Y1806902D01*
X794020D01*
X794080Y1806973D01*
G02X796058Y1807793I1769J-1473D01*
G37*
G36*
G01X646267Y1817848D02*
G03X646443Y1817255I331J-224D01*
G02X643642Y1816423I-894J-2121D01*
G03X643466Y1817016I-331J224D01*
G02X646267Y1817848I894J2121D01*
G37*
G36*
G01X227570Y1873341D02*
X227598Y1873388D01*
Y1875027D01*
X227590Y1875054D01*
G02X232010I2210J646D01*
G01X232002Y1875027D01*
Y1873388D01*
X232030Y1873341D01*
G02X227570I-2230J-1341D01*
G37*
G36*
G01X215870Y1884041D02*
X215898Y1884088D01*
Y1885727D01*
X215890Y1885754D01*
G02X220310I2210J646D01*
G01X220302Y1885727D01*
Y1884088D01*
X220330Y1884041D01*
G02X215870I-2230J-1341D01*
G37*
G36*
G01X229263Y1938786D02*
X226864Y1936387D01*
Y1928295D01*
X226638Y1928069D01*
Y1890465D01*
G02X226621Y1890136I-3202J1D01*
G03X227136Y1889713I398J-41D01*
G02X229671Y1888873I678J-2200D01*
G03X230261Y1888812I323J237D01*
G02X229943Y1885740I1539J-1712D01*
G03X229353Y1885801I-323J-237D01*
G02X225520Y1887317I-1539J1712D01*
G03X224935Y1887636I-398J-35D01*
G02X220234Y1890465I-1499J2829D01*
G01Y1930721D01*
X220460Y1930947D01*
Y1939039D01*
X224735Y1943314D01*
G02X229263Y1938786I2264J-2264D01*
G37*
G36*
G01X861469Y1904091D02*
X861498Y1904138D01*
Y1905777D01*
X861489Y1905804D01*
G02X865909I2210J646D01*
G01X865900Y1905777D01*
Y1904138D01*
X865929Y1904091D01*
G02X861469I-2230J-1341D01*
G37*
G36*
G01X212789Y1910196D02*
X212798Y1910223D01*
Y1912662D01*
X212769Y1912709D01*
G02X217229I2230J1341D01*
G01X217200Y1912662D01*
Y1910223D01*
X217209Y1910196D01*
G02X212789I-2210J-646D01*
G37*
G36*
G01X809659Y1912915D02*
G03Y1912315I264J-300D01*
G02X806213I-1723J-1950D01*
G03Y1912915I-264J300D01*
G02X806026Y1916632I1723J1950D01*
G03X806035Y1917165I-294J272D01*
G02X806061Y1920595I1970J1700D01*
G03X806060Y1921128I-299J266D01*
G02X809941Y1921135I1937J1737D01*
G03X809942Y1920602I299J-266D01*
G02X809915Y1917098I-1937J-1737D01*
G03X809906Y1916565I294J-272D01*
G02X809659Y1912915I-1970J-1700D01*
G37*
G36*
G01X229789Y1914696D02*
X229798Y1914723D01*
Y1916662D01*
X229769Y1916709D01*
G02X234229I2230J1341D01*
G01X234200Y1916662D01*
Y1914723D01*
X234209Y1914696D01*
G02X229789I-2210J-646D01*
G37*
G36*
G01X268722Y1918100D02*
G03Y1917500I264J-300D01*
G02X265276I-1723J-1950D01*
G03Y1918100I-264J300D01*
G02Y1922000I1723J1950D01*
G03Y1922600I-264J300D01*
G02Y1926500I1723J1950D01*
G03Y1927100I-264J300D01*
G02Y1931000I1723J1950D01*
G03Y1931600I-264J300D01*
G02X268722I1723J1950D01*
G03Y1931000I264J-300D01*
G02Y1927100I-1723J-1950D01*
G03Y1926500I264J-300D01*
G02Y1922600I-1723J-1950D01*
G03Y1922000I264J-300D01*
G02Y1918100I-1723J-1950D01*
G37*
G36*
G01X860848Y1919852D02*
X861311D01*
X861374Y1919788D01*
X861428Y1919775D01*
G02X858978Y1915391I-629J-2525D01*
G01X858920Y1915448D01*
X857772D01*
X857745Y1915440D01*
G02Y1919860I-646J2210D01*
G01X857772Y1919852D01*
X860750D01*
G02X860848I49J-2602D01*
G37*
G36*
G01X247269Y1925691D02*
X247298Y1925738D01*
Y1927377D01*
X247289Y1927404D01*
G02X251709I2210J646D01*
G01X251700Y1927377D01*
Y1925738D01*
X251729Y1925691D01*
G02X247269I-2230J-1341D01*
G37*
G36*
G01X862184Y1941391D02*
X862212Y1941438D01*
Y1942662D01*
X862184Y1942709D01*
G02X866644I2230J1341D01*
G01X866616Y1942662D01*
Y1941438D01*
X866644Y1941391D01*
G02X862184I-2230J-1341D01*
G37*
G36*
G01X330171Y1946554D02*
G03X330210Y1946823I-126J156D01*
G02X333554Y1946346I1893J1310D01*
G03X333515Y1946077I126J-156D01*
G02X333294Y1943184I-1893J-1310D01*
G03X333306Y1942622I290J-275D01*
G02X329809Y1942729I-1807J-1872D01*
G03X329857Y1943290I-259J305D01*
G02X330171Y1946554I1765J1477D01*
G37*
G36*
G01X208789Y1942696D02*
X208798Y1942723D01*
Y1944362D01*
X208769Y1944409D01*
G02X213229I2230J1341D01*
G01X213200Y1944362D01*
Y1942723D01*
X213209Y1942696D01*
G02X208789I-2210J-646D01*
G37*
G36*
G01X344371Y1945560D02*
G03X344315Y1944968I238J-321D01*
G02X341249Y1945258I-1694J-1559D01*
G03X341305Y1945850I-238J321D01*
G02X344371Y1945560I1694J1559D01*
G37*
G36*
G01X790268Y1949617D02*
G03X790129Y1949858I-194J49D01*
G02X793405Y1951902I715J2502D01*
G01X793387Y1951799D01*
X793900Y1951286D01*
Y1950879D01*
X793972Y1950819D01*
G02X790268Y1949617I-1473J-1769D01*
G37*
G36*
G01X212032Y1954722D02*
X212057Y1954736D01*
X213876Y1956554D01*
X213885Y1956567D01*
G02X214482Y1957164I2114J-1517D01*
G01X214495Y1957173D01*
X214573Y1957252D01*
X214611D01*
X214658Y1957280D01*
G02X216075Y1952449I1341J-2230D01*
G01X215995Y1952447D01*
X215171Y1951622D01*
X215157Y1951597D01*
G02X212032Y1954722I-2019J1106D01*
G37*
G36*
G01X292237Y1960135D02*
G03X291638Y1960068I-270J-295D01*
G02X288059Y1963717I-2139J1482D01*
G03Y1964383I-222J333D01*
G02X287776Y1968500I1440J2167D01*
G03Y1969100I-264J300D01*
G02X291449Y1972773I1723J1950D01*
G03X292049I300J264D01*
G02X295722Y1969100I1950J-1723D01*
G03Y1968500I264J-300D01*
G02Y1964600I-1723J-1950D01*
G03Y1964000I264J-300D01*
G02X292237Y1960135I-1723J-1950D01*
G37*
G36*
G01X262289Y1964696D02*
X262298Y1964723D01*
Y1966662D01*
X262269Y1966709D01*
G02X266729I2230J1341D01*
G01X266700Y1966662D01*
Y1964723D01*
X266709Y1964696D01*
G02X262289I-2210J-646D01*
G37*
G36*
G01X785537Y1969763D02*
G03Y1969163I264J-300D01*
G02X782091I-1723J-1950D01*
G03Y1969763I-264J300D01*
G02X781964Y1973542I1723J1950D01*
G03X781991Y1974075I-285J282D01*
G02X785866Y1973879I2025J1633D01*
G03X785839Y1973346I285J-282D01*
G02X785537Y1969763I-2025J-1634D01*
G37*
G36*
G01X767741Y1973830D02*
X767788Y1973802D01*
X769261D01*
X769313Y1973838D01*
G02X769412Y1973905I1507J-2121D01*
G03X769546Y1974438I-215J337D01*
G02X773554Y1977647I2268J1274D01*
G03X774087Y1977645I268J298D01*
G02X774074Y1973765I1727J-1946D01*
G03X773541Y1973767I-268J-298D01*
G02X773216Y1973521I-1728J1945D01*
G03X773082Y1972988I215J-337D01*
G02X769666Y1969378I-2268J-1275D01*
G01X769624Y1969398D01*
X767788D01*
X767741Y1969370D01*
G02Y1973830I-1341J2230D01*
G37*
G36*
G01X807100Y1556274D02*
Y1554638D01*
X807129Y1554591D01*
G02X802669I-2230J-1341D01*
G01X802698Y1554638D01*
Y1556274D01*
X802689Y1556302D01*
G02X807109I2210J648D01*
G01X807100Y1556274D01*
G37*
G36*
G01X803180Y1959917D02*
X801763Y1958500D01*
X801747Y1958458D01*
G02X798884Y1961902I-2450J875D01*
G01X798948Y1961912D01*
X800066Y1963031D01*
X800080Y1963056D01*
G02X803205Y1959931I2019J-1106D01*
G01X803180Y1959917D01*
G37*
G36*
G01X345804Y29410D02*
X345751Y29448D01*
X344174D01*
X344146Y29440D01*
G02X341209Y31887I-647J2209D01*
G02X344143Y33860I2290J-237D01*
G01X344171Y33852D01*
X346175D01*
X346215Y33871D01*
G02X349924Y31695I1113J-2352D01*
G02X345804Y29410I-2596J-176D01*
G37*
G36*
G01X45436Y1735411D02*
G03X45164I-136J-147D01*
G02Y1738789I-1564J1689D01*
G03X45436I136J147D01*
G02Y1735411I1564J-1689D01*
G37*
G36*
G01X47573Y1726920D02*
G03Y1726380I295J-270D01*
G02X44181I-1696J-1557D01*
G03Y1726920I-295J270D01*
G02X47573I1696J1557D01*
G37*
G36*
G01X96200Y1668162D02*
Y1667830D01*
X96580Y1667451D01*
X96605Y1667437D01*
G02X93480Y1664312I-1106J-2019D01*
G01X93466Y1664337D01*
X91798Y1666006D01*
Y1668162D01*
X91769Y1668209D01*
G02X96229I2230J1341D01*
G01X96200Y1668162D01*
G37*
G36*
G01X64714Y488008D02*
G03X64707Y487736I143J-140D01*
G02X61331Y487825I-1729J-1519D01*
G03X61338Y488097I-143J140D01*
G02X64714Y488008I1729J1519D01*
G37*
G36*
G01X92585Y483986D02*
G03X92719Y484653I-140J375D01*
G02X95945Y488713I1780J1897D01*
G03X96544Y488913I222J333D01*
G02X97553Y485887I2455J-863D01*
G03X96954Y485687I-222J-333D01*
G02X95413Y484114I-2455J863D01*
G03X95279Y483447I140J-375D01*
G02X95319Y483409I-1772J-1905D01*
G03X95879I280J286D01*
G02X99422Y479600I1820J-1859D01*
G03Y479000I264J-300D01*
G02X95879Y475191I-1723J-1950D01*
G03X95319I-280J-286D01*
G02X91776Y479000I-1820J1859D01*
G03Y479600I-264J300D01*
G02X92585Y483986I1723J1950D01*
G37*
G36*
G01X64189Y472785D02*
G03Y472513I147J-136D01*
G02X60811Y472507I-1686J-1567D01*
G03Y472779I-147J136D01*
G02X64189Y472785I1686J1567D01*
G37*
G36*
G01X182114Y436757D02*
G03X181534I-290J-276D01*
G02X177874Y440452I-1885J1793D01*
G03X177920Y440985I-273J292D01*
G02X178276Y444500I2079J1565D01*
G03Y445100I-264J300D01*
G02X181733Y448990I1723J1950D01*
G03X182265I266J299D01*
G02X185722Y445100I1734J-1940D01*
G03Y444500I264J-300D01*
G02X185939Y440816I-1723J-1950D01*
G03Y440284I299J-266D01*
G02X182114Y436757I-1940J-1734D01*
G37*
G54D34*
X68898Y17047D03*
X167323Y179803D03*
Y353031D03*
Y585315D03*
Y758543D03*
Y1569567D03*
Y1801851D03*
Y1975079D03*
X895669Y179803D03*
Y353031D03*
Y585315D03*
Y758543D03*
Y990827D03*
Y1164055D03*
Y1396339D03*
Y1569567D03*
Y1801851D03*
Y1975079D03*
G54D28*
X950100Y1626100D03*
X904814Y1789113D03*
X903999Y574378D03*
X873499Y1356050D03*
X767999Y1923050D03*
X773999Y1923550D03*
X767159Y1792364D03*
X757500Y1522500D03*
X751499Y679148D03*
X717000Y1812384D03*
X633837Y1807384D03*
X563499Y1503550D03*
X544300Y1784638D03*
X334999Y1797050D03*
X326301Y1766030D03*
X305998Y352114D03*
X307999Y78550D03*
X180000Y1619600D03*
X145649Y509550D03*
X135999Y472550D03*
X135140Y478930D03*
X149700Y471600D03*
X154100Y476500D03*
X164600Y476700D03*
X171300D03*
X154099Y529236D03*
G54D29*
X916499Y172550D03*
X900999Y979050D03*
X900499Y962100D03*
X902999Y556050D03*
X879708Y971892D03*
X883083Y979183D03*
X879950Y565050D03*
X879750Y570550D03*
X854327Y1477550D03*
X852333Y1077716D03*
X852696Y671197D03*
X854400Y264600D03*
X828500Y1877800D03*
X827700Y1487600D03*
X825700Y1083100D03*
X829800Y666650D03*
X827500Y274500D03*
X837999Y219550D03*
X805900Y1887560D03*
X810900Y1882440D03*
X822700Y1871100D03*
X809960Y1478040D03*
X807000Y1072900D03*
X808660Y667540D03*
X809940Y264940D03*
X800431Y1941193D03*
X802499Y1951550D03*
X781999Y725550D03*
X780499Y330050D03*
X758499Y1893550D03*
X757999Y1484050D03*
X757499Y1079550D03*
X733049Y1814134D03*
X733149Y1798634D03*
X732549Y1806634D03*
X707600Y1815600D03*
X400999Y1575550D03*
X402499Y1476850D03*
X394649Y630600D03*
X400499Y406329D03*
X377900Y1703800D03*
X366149Y1554050D03*
X370149Y1320050D03*
X372999Y1123550D03*
X364499Y1099050D03*
X371500Y880600D03*
X375999Y698550D03*
X371999Y549300D03*
X358999Y61550D03*
X354500Y1559500D03*
X347324Y1524000D03*
X345424Y1310050D03*
X345499Y1096550D03*
X340699Y1046086D03*
X350499Y715050D03*
Y597300D03*
X344520Y406329D03*
X330300Y1561200D03*
X326500Y1550200D03*
X320499Y798050D03*
X330540Y795509D03*
X329499Y801550D03*
X323400Y105200D03*
X310499Y1957050D03*
X297499Y97550D03*
X295000Y1513000D03*
X282500Y1135000D03*
X293999Y293550D03*
X282800Y87500D03*
X257499Y1911050D03*
X269500Y1135500D03*
X249600Y1896800D03*
X241000Y1469600D03*
X251500Y1136700D03*
X247500Y1085500D03*
X233500Y1066100D03*
X249800Y689900D03*
X238500Y680800D03*
X249700Y682500D03*
X246800Y677100D03*
X239600Y278600D03*
X250400Y283100D03*
X250300Y275100D03*
X247800Y269700D03*
X224750Y1483950D03*
X226800Y1093400D03*
X221800Y1069300D03*
X220000Y516400D03*
X225298Y281114D03*
X199149Y1362900D03*
X199900Y554050D03*
X177900Y1690400D03*
X181100Y1682700D03*
X174250Y1694500D03*
X171999Y1662250D03*
X179499Y1275550D03*
X183499Y556100D03*
X173500Y166315D03*
X152633Y1677967D03*
X156500Y554000D03*
X137899Y545451D03*
X135499Y517550D03*
X107000Y604800D03*
X105100Y600000D03*
X89800Y208550D03*
X95350Y204550D03*
X97499Y90050D03*
X65999Y216050D03*
X24244Y1681868D03*
X42199Y1601050D03*
X98599Y1491350D03*
X163449Y521650D03*
G54D32*
X886417Y1963268D03*
Y1813662D03*
Y1557756D03*
Y1408150D03*
Y1152244D03*
Y1002638D03*
Y746732D03*
Y597126D03*
Y341220D03*
Y191614D03*
X158071Y1963268D03*
Y1813662D03*
Y1557756D03*
Y597126D03*
Y341220D03*
Y191614D03*
X78150Y178464D03*
Y28858D03*
Y1650906D03*
G54D33*
X9843Y1859468D03*
Y353144D03*
Y1746869D03*
G54D31*
X1019291Y1416024D03*
G54D30*
X1008999Y1968550D03*
X1010999Y18550D03*
X21499Y17050D03*
G54D27*
X994093Y1889751D03*
X994098Y1068880D03*
Y673210D03*
Y149588D03*
X271657Y1484234D03*
Y1078722D03*
Y673210D03*
Y267699D03*
X29531Y309549D03*
%LPD*%
G75*
G36*
G01X201999Y72550D02*
X202999Y71550D01*
Y58550D01*
X182999Y38550D01*
X109999D01*
X106999Y41550D01*
Y68550D01*
X110999Y72550D01*
X201999D01*
G37*
G36*
G01X108499Y74550D02*
X106999Y76050D01*
Y114050D01*
X111499Y118550D01*
X179499D01*
X180999Y117050D01*
Y109050D01*
X170499Y98550D01*
Y77050D01*
X167999Y74550D01*
X108499D01*
G37*
G36*
G01X187499Y18550D02*
X183999Y22050D01*
Y37050D01*
X195499Y48550D01*
X208999D01*
X211999Y45550D01*
Y20550D01*
X209999Y18550D01*
X187499D01*
G37*
G36*
G01X172798Y77612D02*
X175975Y74434D01*
G02X175692Y73752I-283J-282D01*
G01X169865D01*
G02X169582Y74434I0J400D01*
G01X171700Y76552D01*
X171701Y86291D01*
G02X172383Y86574I400J0D01*
G01X173466Y85491D01*
X173480Y85466D01*
G03X176265Y84401I2019J1106D01*
G02X176798Y84024I133J-377D01*
G01Y81362D01*
G02X176190Y81020I-400J0D01*
G03X172789Y78404I-1191J-1970D01*
G01X172798Y78377D01*
Y77612D01*
G37*
G36*
G01X177819Y97756D02*
X187211Y107148D01*
X193111D01*
X193158Y107120D01*
G03X195840I1341J2230D01*
G01X195887Y107148D01*
X203077D01*
G02X203436Y106571I1J-400D01*
G03X206145Y103340I2063J-1021D01*
G01X206172Y103348D01*
X208118D01*
G02X208401Y102666I0J-400D01*
G01X206987Y101252D01*
X196887D01*
X196840Y101280D01*
G03X194158I-1341J-2230D01*
G01X194111Y101252D01*
X187672D01*
X187645Y101260D01*
G03X184980Y100156I-646J-2210D01*
G01X184966Y100131D01*
X184326Y99491D01*
Y82965D01*
X181883Y80522D01*
G02X181200Y80805I-283J283D01*
G01Y87162D01*
X181229Y87209D01*
G03Y89891I-2230J1341D01*
G01X181200Y89938D01*
Y94784D01*
X178911Y97074D01*
X178102D01*
G02X177819Y97756I0J400D01*
G37*
G36*
G01X212615Y46633D02*
X209497Y49752D01*
X196865D01*
G02X196582Y50434I0J400D01*
G01X204200Y58052D01*
Y72048D01*
X202497Y73752D01*
X182306D01*
G02X182023Y74434I0J400D01*
G01X188730Y81141D01*
Y96848D01*
X194111D01*
X194158Y96820D01*
G03X196840I1341J2230D01*
G01X196887Y96848D01*
X208811D01*
X214580Y102617D01*
X214605Y102631D01*
G03X215447Y103424I-1107J2018D01*
G02X216068Y103493I338J-214D01*
G01X223298Y96264D01*
Y74252D01*
X220001D01*
X217798Y72048D01*
Y56048D01*
X213298Y51548D01*
X213297Y46916D01*
G02X212615Y46633I-400J0D01*
G37*
G36*
G01X235999Y72050D02*
Y33050D01*
X233999Y31050D01*
X214999D01*
X214499Y31550D01*
Y51050D01*
X218999Y55550D01*
Y71550D01*
X220499Y73050D01*
X234999D01*
X235999Y72050D01*
G37*
G36*
G01X364499Y116550D02*
Y100050D01*
X362999Y98550D01*
X343499D01*
X270499Y171550D01*
X221499D01*
X220999Y172050D01*
Y195550D01*
X223999Y198550D01*
X282499D01*
X364499Y116550D01*
G37*
G36*
G01X291200Y26400D02*
X289499Y28101D01*
Y35050D01*
X303499Y49050D01*
X310999D01*
X311999Y48050D01*
Y33050D01*
X305349Y26400D01*
X291200D01*
G37*
G36*
G01X886499Y77050D02*
X895499Y86050D01*
X919499D01*
X920499Y85050D01*
Y61550D01*
X895499Y36550D01*
X839499D01*
X835999Y40050D01*
Y76050D01*
X836999Y77050D01*
X886499D01*
G37*
G36*
G01X882999Y79550D02*
X836999D01*
X834999Y81550D01*
Y126050D01*
X837999Y129050D01*
X891999D01*
X893499Y127550D01*
Y90050D01*
X882999Y79550D01*
G37*
G36*
G01X923115Y49633D02*
X921497Y51252D01*
X912865D01*
G02X912582Y51934I0J400D01*
G01X921700Y61052D01*
Y85548D01*
X919997Y87252D01*
X895001D01*
X886001Y78252D01*
X884365D01*
G02X884082Y78934I0J400D01*
G01X894700Y89552D01*
X894701Y89752D01*
G02X895042Y89894I200J0D01*
G01X895522Y89413D01*
X895536Y89388D01*
G03X899759Y89829I2019J1106D01*
G02X900343Y90059I383J-116D01*
G03X903518Y90944I1156J1991D01*
G01X903532Y90969D01*
X903800Y91238D01*
Y92002D01*
X903801Y92004D01*
G03Y92096I-2302J46D01*
G01X903800Y92098D01*
Y101362D01*
X901461Y103701D01*
X901495Y103815D01*
G03X901229Y105891I-2496J735D01*
G01X901200Y105938D01*
Y107769D01*
G02X901883Y108052I400J0D01*
G01X905087Y104848D01*
X917111D01*
X917158Y104820D01*
G03X919840I1341J2230D01*
G01X919887Y104848D01*
X929411D01*
X936700Y112138D01*
Y113238D01*
G02X937308Y113580I400J0D01*
G03X940406Y114261I1191J1970D01*
G01X940465Y114348D01*
X944111D01*
X944158Y114320D01*
G03X946840I1341J2230D01*
G01X946887Y114348D01*
X952587D01*
X963298Y103638D01*
Y95552D01*
X962172D01*
X962145Y95560D01*
G03Y91140I-646J-2210D01*
G01X962172Y91148D01*
X963518D01*
G02X963801Y90466I0J-400D01*
G01X963587Y90252D01*
X948087D01*
X945087Y87252D01*
X936001D01*
X930798Y82048D01*
Y73048D01*
X923798Y66048D01*
Y49916D01*
G02X923115Y49633I-400J0D01*
G37*
G36*
G01X900499Y15050D02*
X897999Y17550D01*
Y37050D01*
X910999Y50050D01*
X920999D01*
X922499Y48550D01*
Y17550D01*
X919999Y15050D01*
X900499D01*
G37*
G36*
G01X898636Y92527D02*
X898000Y93162D01*
Y99969D01*
G02X898683Y100252I400J0D01*
G01X899398Y99538D01*
Y92991D01*
X899381Y92953D01*
G03X899295Y92715I2119J-900D01*
G02X898711Y92485I-383J116D01*
G03X898661Y92513I-1150J-1994D01*
G01X898636Y92527D01*
G37*
G36*
G01X911999Y121937D02*
X921087Y112848D01*
X926326D01*
X926353Y112840D01*
G03X928893Y113742I645J2210D01*
G02X929485Y113816I329J-228D01*
G03X930695Y113268I1514J1734D01*
G02X930925Y112589I-53J-396D01*
G01X927587Y109252D01*
X919887D01*
X919840Y109280D01*
G03X917158I-1341J-2230D01*
G01X917111Y109252D01*
X906911D01*
X904532Y111631D01*
X904518Y111656D01*
G03X900889Y112195I-2019J-1106D01*
G02X900609I-140J143D01*
G03X898489Y112795I-1610J-1645D01*
G02X898000Y113185I-89J390D01*
G01Y117438D01*
X899911Y119348D01*
X903111D01*
X903158Y119320D01*
G03X905840I1341J2230D01*
G01X905887Y119348D01*
X909411D01*
X911999Y121937D01*
G37*
G36*
G01X935038Y84589D02*
X936499Y86050D01*
X953499D01*
X954499Y85050D01*
Y34050D01*
X950999Y30550D01*
X926999D01*
X924999Y32550D01*
Y65550D01*
X931999Y72550D01*
Y81550D01*
X933953Y83504D01*
X933983Y83519D01*
G03X935023Y84559I-1022J2062D01*
G01X935038Y84589D01*
G37*
G36*
G01X948673Y123348D02*
X952587Y119434D01*
G02X952304Y118752I-283J-282D01*
G01X946887D01*
X946840Y118780D01*
G03X944158I-1341J-2230D01*
G01X944111Y118752D01*
X940200D01*
Y121377D01*
X940209Y121404D01*
G03X940170Y122816I-2210J646D01*
G02X940547Y123348I377J132D01*
G01X948673D01*
G37*
%LPC*%
G75*
G54D28*
X168499Y65550D03*
X191999Y68050D03*
%LPD*%
G75*
G54D10*
X-38666Y47522D03*
X-37468Y1947630D03*
X21499Y17050D03*
X1010999Y18550D03*
X1008999Y1968550D03*
X1073242Y50048D03*
G54D11*
X-38436Y23633D03*
X-36811Y1104775D03*
X-35919Y1969497D03*
X9843Y353144D03*
Y717711D03*
Y762617D03*
Y875216D03*
Y1337396D03*
Y1701963D03*
Y1746869D03*
Y1859468D03*
X78150Y28858D03*
Y178464D03*
Y434370D03*
Y583976D03*
Y839882D03*
Y989488D03*
Y1245394D03*
Y1395000D03*
Y1650906D03*
Y1800512D03*
X158071Y191614D03*
Y341220D03*
Y597126D03*
Y746732D03*
Y1002638D03*
Y1152244D03*
Y1408150D03*
Y1557756D03*
Y1813662D03*
Y1963268D03*
X886417Y191614D03*
Y341220D03*
Y597126D03*
Y746732D03*
Y1002638D03*
Y1152244D03*
Y1408150D03*
Y1557756D03*
Y1813662D03*
Y1963268D03*
X1019291Y1416024D03*
Y1694212D03*
X1072493Y21507D03*
X1075940Y1769358D03*
G54D20*
X1005807Y1636102D03*
Y1631102D03*
Y1626102D03*
Y1621102D03*
Y1661102D03*
Y1656102D03*
Y1651102D03*
Y1646102D03*
Y1641102D03*
Y1676102D03*
Y1671102D03*
Y1666102D03*
G54D21*
G01X-87137Y-139897D02*
Y-107897D01*
G01X-75137Y-123897D02*
G02I-12000J0D01*
G01X-80287D02*
G02I-6850J0D01*
G01X-71137D02*
X-103137D01*
G01X-71137Y-139897D02*
Y-219897D01*
G01D02*
X1129963D01*
G01X-71137Y-175397D02*
X1129963D01*
G01X-71137Y-139897D02*
X1129963D01*
G01X23399Y389679D02*
X21515Y387795D01*
X11075D01*
X11069Y387789D01*
G01X23499Y381831D02*
X21472Y383858D01*
X11075D01*
X11069Y383852D01*
G01X23399Y373931D02*
X21515Y372047D01*
X11075D01*
X11069Y372041D01*
G01X23799Y405684D02*
X21658Y403543D01*
X11075D01*
X11069Y403537D01*
G01X23499Y397579D02*
X21472Y399606D01*
X11075D01*
X11069Y399600D01*
G01X23399Y429051D02*
X21515Y427167D01*
X11075D01*
X11069Y427161D01*
G01X23499Y452699D02*
X21472Y454726D01*
X11075D01*
X11069Y454720D01*
G01X23399Y444799D02*
X21515Y442915D01*
X11075D01*
X11069Y442909D01*
G01X23499Y436951D02*
X21472Y438978D01*
X11075D01*
X11069Y438972D01*
G01X23399Y476295D02*
X21515Y474411D01*
X11075D01*
X11069Y474405D01*
G01X23499Y468447D02*
X21472Y470474D01*
X11075D01*
X11069Y470468D01*
G01X23399Y460547D02*
X21515Y458663D01*
X11075D01*
X11069Y458657D01*
G01X23399Y492043D02*
X21515Y490159D01*
X11075D01*
X11069Y490153D01*
G01X23499Y484195D02*
X21472Y486222D01*
X11075D01*
X11069Y486216D01*
G01X23499Y515691D02*
X21472Y517718D01*
X11075D01*
X11069Y517712D01*
G01X23399Y507791D02*
X21515Y505907D01*
X11075D01*
X11069Y505901D01*
G01X23499Y499943D02*
X21472Y501970D01*
X11075D01*
X11069Y501964D01*
G01X23499Y531439D02*
X21472Y533466D01*
X11075D01*
X11069Y533460D01*
G01X23399Y523539D02*
X21515Y521655D01*
X11075D01*
X11069Y521649D01*
G01X22699Y577950D02*
X21522Y576773D01*
X11075D01*
X11069Y576767D01*
G01X22978Y588571D02*
X22965Y588584D01*
X11075D01*
X11069Y588578D01*
G01X23799Y625950D02*
X21866Y624017D01*
X11075D01*
X11069Y624011D01*
G01X23499Y618053D02*
X21472Y620080D01*
X11075D01*
X11069Y620074D01*
G01X23999Y609250D02*
X23018Y608269D01*
X11075D01*
X11069Y608263D01*
G01X23399Y641649D02*
X21515Y639765D01*
X11075D01*
X11069Y639759D01*
G01X23499Y633801D02*
X21472Y635828D01*
X11075D01*
X11069Y635822D01*
G01X23725Y657471D02*
X21767Y655513D01*
X11075D01*
X11069Y655507D01*
G01X23499Y649549D02*
X21373Y651675D01*
X21274Y651576D01*
X11075D01*
X11069Y651570D01*
G01X23499Y681045D02*
X21472Y683072D01*
X11075D01*
X11069Y683066D01*
G01X23699Y673150D02*
X21810Y671261D01*
X11075D01*
X11069Y671255D01*
G01X23499Y665297D02*
X21472Y667324D01*
X11075D01*
X11069Y667318D01*
G01X23700Y1354600D02*
X22001Y1356299D01*
X11075D01*
X11069Y1356293D01*
G01X23499Y1381550D02*
Y1382501D01*
X22142Y1383858D01*
X11075D01*
X11069Y1383852D01*
G01X22851Y1374169D02*
X20729Y1372047D01*
X11075D01*
X11069Y1372041D01*
G01X22999Y1366050D02*
X20939Y1368110D01*
X11075D01*
X11069Y1368104D01*
G01X24499Y1389663D02*
X22631Y1387795D01*
X11075D01*
X11069Y1387789D01*
G01X23999Y1429050D02*
X22116Y1427167D01*
X11075D01*
X11069Y1427161D01*
G01X23499Y1421550D02*
X21819Y1423230D01*
X11075D01*
X11069Y1423224D01*
G01X23999Y1413550D02*
X21868Y1411419D01*
X11075D01*
X11069Y1411413D01*
G01X23499Y1445050D02*
Y1444650D01*
X21764Y1442915D01*
X11075D01*
X11069Y1442909D01*
G01X22999Y1437050D02*
X20972Y1439077D01*
X20873Y1438978D01*
X11075D01*
X11069Y1438972D01*
G01X23028Y1468579D02*
X21034Y1470573D01*
X20935Y1470474D01*
X11075D01*
X11069Y1470468D01*
G01X23499Y1460550D02*
X21612Y1458663D01*
X11075D01*
X11069Y1458657D01*
G01X22999Y1453050D02*
X21224Y1454825D01*
X21125Y1454726D01*
X11075D01*
X11069Y1454720D01*
G01X24499Y1492050D02*
X22608Y1490159D01*
X11075D01*
X11069Y1490153D01*
G01X23277Y1484050D02*
X21105Y1486222D01*
X11075D01*
X11069Y1486216D01*
G01X23599Y1476350D02*
X21660Y1474411D01*
X11075D01*
X11069Y1474405D01*
G01X23799Y1508050D02*
Y1507450D01*
X22256Y1505907D01*
X11075D01*
X11069Y1505901D01*
G01X22999Y1500050D02*
X21079Y1501970D01*
X11075D01*
X11069Y1501964D01*
G01X22999Y1515550D02*
X20831Y1517718D01*
X11075D01*
X11069Y1517712D01*
G01X23608Y1572653D02*
X23425Y1572836D01*
X11075D01*
X11069Y1572830D01*
G01X24323Y1559950D02*
X23248Y1561025D01*
X11075D01*
X11069Y1561019D01*
G01X22699Y1594224D02*
X20996Y1592521D01*
X11075D01*
X11069Y1592515D01*
G01X23499Y1610050D02*
X21718Y1608269D01*
X11075D01*
X11069Y1608263D01*
G01X23499Y1602050D02*
X21217Y1604332D01*
X11075D01*
X11069Y1604326D01*
G01X23415Y1641634D02*
X21546Y1639765D01*
X11075D01*
X11069Y1639759D01*
G01X23499Y1634050D02*
X21721Y1635828D01*
X11075D01*
X11069Y1635822D01*
G01X22999Y1626050D02*
X20966Y1624017D01*
X11075D01*
X11069Y1624011D01*
G01X23499Y1618050D02*
X21469Y1620080D01*
X11075D01*
X11069Y1620074D01*
G01X23499Y1657050D02*
X21962Y1655513D01*
X11075D01*
X11069Y1655507D01*
G01X23999Y1649550D02*
X21973Y1651576D01*
X11075D01*
X11069Y1651570D01*
G01X22999Y1665550D02*
X21225Y1667324D01*
X11075D01*
X11069Y1667318D01*
G01X5303Y1947050D02*
Y1945354D01*
X5299Y1945350D01*
Y1936223D01*
X7172Y1934350D01*
X7647D01*
X12348Y1929649D01*
X16587D01*
X17455Y1928781D01*
G01X23030Y1922038D02*
Y1923206D01*
X17455Y1928781D01*
G01X11703Y1951946D02*
Y1942702D01*
X11699Y1942698D01*
Y1934824D01*
X13674Y1932849D01*
X23999D01*
G01X8499Y1937550D02*
Y1944024D01*
X8503Y1944028D01*
Y1961606D01*
X25416Y1978519D01*
X31268D01*
X31799Y1979050D01*
G01X15099Y1944050D02*
Y1953250D01*
X13799Y1954550D01*
Y1962376D01*
X19172Y1967749D01*
X37499D01*
G01X14999Y1936050D02*
X18299Y1939350D01*
Y1956750D01*
X16999Y1958050D01*
Y1960550D01*
X17499Y1961050D01*
G01D02*
Y1961550D01*
X20498Y1964549D01*
X32999D01*
G01X48499Y1897050D02*
X43472D01*
X38999Y1901523D01*
Y1921050D01*
X27200Y1932849D01*
X23999D01*
G01X26765Y1921945D02*
X29591D01*
X34970Y1916566D01*
Y1901026D01*
X44946Y1891050D01*
X47999D01*
G01X42499Y1902550D02*
Y1923550D01*
X35521Y1930528D01*
G01X25499Y1956050D02*
Y1940550D01*
X35521Y1930528D01*
G01X47598Y1961550D02*
X41399Y1967749D01*
X37499D01*
G01X43462Y1961160D02*
X40073Y1964549D01*
X32999D01*
G01Y1960555D02*
Y1956855D01*
G01X57999Y1891050D02*
X47999D01*
G01X50499Y1961550D02*
X47598D01*
G01X67000Y1011500D02*
X67211D01*
X78099Y1000612D01*
Y999373D01*
X96972Y980500D01*
X104600D01*
G01X106700Y997800D02*
X92779Y1011721D01*
X76040D01*
X75500Y1012261D01*
G01X90000Y854500D02*
X92450Y852050D01*
X93795D01*
X93808Y852063D01*
G01X93299Y862050D02*
X96000Y864751D01*
Y866000D01*
G01X93900Y882400D02*
X93750Y882550D01*
X88999D01*
G01X93499Y892050D02*
X89499D01*
G01X107300Y986000D02*
X105900Y987400D01*
Y987500D01*
X99200Y994200D01*
G01D02*
Y1000400D01*
X91100Y1008500D01*
X88000D01*
G01X101541Y1262607D02*
X102556D01*
X104999Y1265050D01*
G01X101399Y1292550D02*
X105499D01*
G01X95499Y1665418D02*
X93999Y1666918D01*
Y1669550D01*
G01Y1703050D02*
X89999D01*
G01X90000Y1827900D02*
Y1831200D01*
X89200Y1832000D01*
G01X106700Y997800D02*
Y993600D01*
X107400Y992900D01*
G01X116999Y1288050D02*
X116499D01*
X113999Y1285550D01*
G01X118499Y1694050D02*
Y1697750D01*
G01X136349Y509050D02*
X132349D01*
G01X138416Y553500D02*
X138116Y553800D01*
X134700D01*
G01X141300Y565900D02*
Y566200D01*
X137100Y570400D01*
Y570500D01*
G01X140000Y1332600D02*
X139400Y1332900D01*
X136783Y1335517D01*
G01X143500Y1323500D02*
X144000Y1323000D01*
X146000D01*
X147400Y1321600D01*
G01X154200Y168500D02*
X156817Y165883D01*
G01X149400Y166400D02*
Y162500D01*
G01X153499Y502550D02*
X157499D01*
G01X157000Y573851D02*
X156700Y574000D01*
X153000D01*
G01X160824Y577000D02*
X160900Y576700D01*
Y573000D01*
G01X186999Y99050D02*
X186528Y98579D01*
Y82053D01*
X180325Y75850D01*
X177673D01*
X174999Y78524D01*
Y79050D01*
G01X175499Y86572D02*
X173199Y88872D01*
Y96199D01*
X174999Y97999D01*
Y98050D01*
X186299Y109350D01*
X194499D01*
G01X178999Y79050D02*
Y88550D01*
G01X176399Y94872D02*
X177999D01*
X178999Y93872D01*
Y88550D01*
G01X195499Y99050D02*
X186999D01*
G01X181000Y1365500D02*
Y1361000D01*
G01X180400Y1374000D02*
Y1370000D01*
X180500Y1369900D01*
G01X213499Y104650D02*
X207899Y99050D01*
X195499D01*
G01X188999Y120800D02*
X193749D01*
X197999Y116550D01*
X204499D01*
G01X205499Y105550D02*
X209473D01*
X211773Y107850D01*
X214825D01*
X225499Y97176D01*
Y68550D01*
G01X194499Y109350D02*
X207799D01*
X207999Y109550D01*
G01D02*
X208947D01*
X210447Y111050D01*
X216151D01*
X221651Y105550D01*
X236399D01*
X237899Y107050D01*
G01X223499Y108150D02*
Y108750D01*
X215699Y116550D01*
X204499D01*
G01X230749Y76300D02*
X241099Y86650D01*
Y95050D01*
G01X229800Y1073600D02*
Y1077300D01*
G01Y1872000D02*
Y1875700D01*
G01X218100Y1886400D02*
Y1882700D01*
G01X214999Y1909550D02*
Y1914050D01*
G01X215999Y1955050D02*
X215485D01*
X213138Y1952703D01*
G01X210999Y1942050D02*
Y1945750D01*
G01X233749Y110800D02*
X238675D01*
X241099Y108376D01*
Y95050D01*
G01X242000Y1066000D02*
Y1069700D01*
G01X231999Y1914050D02*
Y1918050D01*
G01X249499Y1928050D02*
Y1924350D01*
G01X264499Y1964050D02*
Y1968050D01*
G01X289999Y72550D02*
X285999D01*
G01X308499D02*
X312499D01*
G01X354999Y72050D02*
X348499D01*
X335574Y84975D01*
X311074D01*
X308999Y87050D01*
G01X324800Y89400D02*
Y93100D01*
G01X315800Y100500D02*
Y104200D01*
G01X342463Y-139897D02*
Y-219897D01*
G01X343499Y31650D02*
X347197D01*
X347328Y31519D01*
G01X479963Y-139897D02*
Y-219897D01*
G01X594963Y-139897D02*
Y-219897D01*
G01X822100Y279500D02*
X773049D01*
X751539Y301010D01*
Y313984D01*
G01X762463Y-139897D02*
Y-219897D01*
G01X766400Y1971600D02*
X770701D01*
X770814Y1971713D01*
G01X799385Y757436D02*
Y761436D01*
G01X799297Y1959333D02*
X799482D01*
X802099Y1961950D01*
G01X822100Y261700D02*
X822200Y261600D01*
Y258000D01*
G01X842499Y280924D02*
X841075Y279500D01*
X822100D01*
G01X816700Y274300D02*
X816500Y274100D01*
Y270600D01*
G01X820600Y664300D02*
X820900Y664600D01*
Y668000D01*
G01X813200Y675900D02*
X812800Y676200D01*
Y679900D01*
G01X815400Y1082500D02*
Y1078800D01*
G01X803199Y1151850D02*
X806899D01*
G01X804899Y1553250D02*
Y1556950D01*
G01X825800Y1072300D02*
X825500Y1072600D01*
Y1076300D01*
G01X834799Y1946950D02*
Y1950835D01*
X835114Y1951150D01*
G01X865499Y288050D02*
X869325D01*
X869399Y288124D01*
G01X867899Y321550D02*
X864225D01*
X864199Y321524D01*
G01X864499Y1128750D02*
X868199D01*
X868399Y1128950D01*
G01X863699Y1501250D02*
X863799D01*
X866516Y1498533D01*
G01X864799Y1532050D02*
Y1532750D01*
X867199Y1535150D01*
G01X867523Y1542821D02*
X864181D01*
X863838Y1542478D01*
G01X862800Y1712700D02*
X862599D01*
X860085Y1715214D01*
G01X863699Y1902750D02*
Y1906450D01*
G01X857099Y1917650D02*
X860399D01*
X860799Y1917250D01*
G01X864414Y1940050D02*
Y1944050D01*
G01X868799Y294750D02*
X872873D01*
X872999Y294624D01*
G01X868299Y336150D02*
X872525D01*
X872599Y336224D01*
G01X870499Y724550D02*
X866499D01*
G01X870294Y1375659D02*
X866968D01*
X866596Y1375796D01*
G01X886439Y1717600D02*
X887000Y1718161D01*
Y1721400D01*
G01X873800Y1733600D02*
Y1733800D01*
X871283Y1736317D01*
G01X901499Y92050D02*
X901599Y92150D01*
Y100450D01*
X898999Y103050D01*
Y104550D01*
G01X897555Y90494D02*
X895799Y92250D01*
Y118350D01*
X898999Y121550D01*
X904499D01*
G01X902499Y110550D02*
X905999Y107050D01*
X918499D01*
G01X898999Y110550D02*
Y104550D01*
G01X907499Y131800D02*
X911749D01*
X919542Y124007D01*
G01X910999Y124550D02*
Y124050D01*
X908499Y121550D01*
X904499D01*
G01X889800Y1711500D02*
X892517Y1714217D01*
G01X934499Y118750D02*
Y113050D01*
X928499Y107050D01*
X918499D01*
G01X926999Y115050D02*
X921999D01*
X912499Y124550D01*
X910999D01*
G01X930999Y115550D02*
X927999Y118550D01*
X924999D01*
X919542Y124007D01*
G01X926999Y122050D02*
X927499D01*
X930999Y125550D01*
X949585D01*
X961568Y113567D01*
G01X932463Y-139897D02*
Y-219897D01*
G01X943499Y82550D02*
X948999Y88050D01*
X964499D01*
X968699Y92250D01*
Y106436D01*
X961568Y113567D01*
G01X937999Y122050D02*
Y117050D01*
X938499Y116550D01*
Y115550D01*
G01D02*
X939499Y116550D01*
X945499D01*
G01X961499Y93350D02*
X964299D01*
X965499Y94550D01*
Y104550D01*
X953499Y116550D01*
X945499D01*
G01X1129963Y-139897D02*
Y-219897D01*
G01X1157963Y-123897D02*
G02I-12000J0D01*
G01X1152813D02*
G02I-6850J0D01*
G01X1161963D02*
X1129963D01*
G01X1145963Y-139897D02*
Y-107897D01*
G54D12*
X17600Y5604D03*
X10000Y16500D03*
X11999Y53550D03*
X11499Y34050D03*
X11999Y69050D03*
Y88550D03*
X11499Y106050D03*
X11999Y124550D03*
X11499Y142050D03*
X11999Y177050D03*
Y161550D03*
Y196550D03*
X11499Y214050D03*
X9499Y229050D03*
X8999Y246550D03*
X9499Y281550D03*
Y266050D03*
Y301050D03*
X15499Y328050D03*
X8999Y318550D03*
X15499Y342550D03*
Y360050D03*
X14799Y751450D03*
X8599Y751650D03*
X17299Y773950D03*
X10999Y774050D03*
X8999Y889550D03*
X8499Y907050D03*
X8999Y942050D03*
Y926550D03*
Y961550D03*
X8499Y979050D03*
X8999Y988550D03*
Y1025550D03*
X8499Y1006050D03*
X8999Y1041050D03*
Y1060550D03*
X8499Y1089050D03*
Y1078050D03*
X7999Y1106550D03*
X8499Y1126050D03*
Y1141550D03*
Y1161050D03*
X7999Y1192550D03*
Y1178550D03*
X7499Y1210050D03*
X7999Y1229550D03*
Y1245050D03*
Y1264550D03*
X7499Y1282050D03*
X8299Y1320050D03*
X8799Y1302550D03*
X18099Y1343550D03*
X9399Y1347350D03*
X15299Y1723450D03*
X15399Y1708350D03*
X7099Y1717750D03*
X7199Y1731450D03*
X14899Y1736250D03*
X15299Y1753250D03*
X6099Y1753750D03*
X11299Y1850050D03*
X9099Y1881550D03*
X17455Y1928781D03*
X8499Y1979550D03*
X11500Y1987000D03*
X36000Y5604D03*
X23499Y27050D03*
X40999Y27550D03*
X27799Y38450D03*
X40999Y42050D03*
X25799Y64050D03*
X28399Y94950D03*
X34999Y108550D03*
X41399Y134150D03*
X27999Y131050D03*
Y145550D03*
Y163050D03*
X23999Y243550D03*
Y229050D03*
Y261050D03*
X39999Y327550D03*
Y342050D03*
Y359550D03*
X33799Y553050D03*
X37849Y561450D03*
X31549Y566050D03*
X39999Y576550D03*
X32505Y592986D03*
X32300Y597800D03*
X35766Y602721D03*
X35157Y608117D03*
X36999Y725050D03*
Y719550D03*
X37499Y714050D03*
X41499Y719550D03*
X26399Y750850D03*
X36499Y740050D03*
Y732550D03*
X39899Y754850D03*
X39399Y768750D03*
X27199Y764950D03*
X28599Y775450D03*
X26799Y874550D03*
X26099Y891650D03*
X25699Y916150D03*
X25099Y942150D03*
X23899Y957950D03*
X24799Y992250D03*
X33899Y1005950D03*
X21499Y1073250D03*
X21399Y1090850D03*
X21299Y1300250D03*
X21799Y1282750D03*
X37173Y1583074D03*
X40200Y1586800D03*
X40299Y1828750D03*
X31499Y1849750D03*
X39399Y1864350D03*
X23999Y1857950D03*
X27199Y1874350D03*
X34799Y1890050D03*
X35521Y1930528D03*
X23999Y1932849D03*
X32999Y1956855D03*
X37499Y1967749D03*
X32999Y1964549D03*
X26500Y1987000D03*
X55700Y5900D03*
X50999Y21150D03*
Y47750D03*
X46499Y69050D03*
X59499Y90550D03*
Y76050D03*
Y108050D03*
X52499Y130550D03*
Y145050D03*
Y162550D03*
X41699Y183250D03*
X48499Y243050D03*
Y228550D03*
Y260550D03*
X42999Y275650D03*
X51099Y300050D03*
X52199Y342350D03*
X57300Y452700D03*
X42299Y564150D03*
X62055Y561550D03*
X49555Y563550D03*
X61099Y603236D03*
X52333Y641295D03*
X43499Y657550D03*
X47800Y692800D03*
X53210Y701486D03*
X56500Y724500D03*
X50999Y720050D03*
X46499Y719550D03*
X51499Y724550D03*
X46499D03*
X41999D03*
X46499Y730550D03*
X53999Y732050D03*
X53499Y739468D03*
X41999Y735050D03*
Y731050D03*
X46499Y735050D03*
X41999Y739550D03*
X46499Y739050D03*
X51999Y767050D03*
X47999Y767550D03*
X52499Y771550D03*
X47999D03*
X53999Y791000D03*
X43300Y806300D03*
X52299Y801450D03*
X59800Y812750D03*
X54000Y819900D03*
X44899Y836250D03*
X54799Y838050D03*
X50399Y841450D03*
X55299Y844350D03*
X61600Y850531D03*
X47200Y848431D03*
X41325Y1548747D03*
X60000Y1535500D03*
X56499Y1597069D03*
X46425Y1586470D03*
X60700Y1578962D03*
X49999Y1633069D03*
X56999Y1663550D03*
X42999Y1694569D03*
X50199Y1836052D03*
X49616Y1842667D03*
X52999Y1871550D03*
X57499Y1871050D03*
X45699Y1875550D03*
X47999Y1891050D03*
X47499Y1915050D03*
X54999Y1931550D03*
X47499Y1930550D03*
X62499Y1939550D03*
X58999Y1958050D03*
X61500Y1987500D03*
X44500Y1987000D03*
X55999Y1982550D03*
X73900Y6200D03*
X65499Y27050D03*
Y41550D03*
Y59050D03*
X77165Y110799D03*
X71015Y123666D03*
X78165Y137116D03*
X75299Y261750D03*
X76099Y414250D03*
X75300Y454100D03*
X67300Y450200D03*
X68899Y445450D03*
X68800Y454300D03*
X66099Y500950D03*
X77165Y514650D03*
X70800Y540300D03*
X75999Y556640D03*
X66500Y543000D03*
X73000Y548700D03*
X72599Y578236D03*
X79299Y794150D03*
X67999Y790400D03*
X76399Y820450D03*
X70100Y818900D03*
X77499Y921550D03*
X77002Y952079D03*
X76711Y948089D03*
X77499Y962152D03*
X72799Y982950D03*
X65799Y994050D03*
X72300Y1018000D03*
X66000Y1020350D03*
X70999Y1025550D03*
X67000Y1011500D03*
X77165Y1327335D03*
X77166Y1353400D03*
X76499Y1507050D03*
Y1498050D03*
Y1512050D03*
Y1503050D03*
X76999Y1528050D03*
Y1519050D03*
X81999Y1541550D03*
X72599Y1546650D03*
X70099Y1540550D03*
X78400Y1566400D03*
X74600Y1557500D03*
X78462Y1574918D03*
X81499Y1589050D03*
X83499Y1594050D03*
X78999Y1593550D03*
X74999D03*
X73499Y1613069D03*
X74499Y1602050D03*
Y1598050D03*
X83499D03*
Y1602050D03*
X78999Y1598050D03*
Y1602050D03*
X65000Y1697500D03*
X83599Y1744750D03*
X77165Y1759550D03*
X78529Y1788113D03*
X62399Y1776050D03*
X68999Y1773550D03*
X62300Y1789650D03*
X78999Y1891550D03*
X82999D03*
Y1887550D03*
X78999D03*
X62999Y1914550D03*
X78999Y1896050D03*
X78433Y1900010D03*
X78999Y1904050D03*
X83499Y1896050D03*
X83433Y1904010D03*
X69499Y1918050D03*
X81999Y1934050D03*
X62999Y1926050D03*
X81499Y1915550D03*
X82499Y1957050D03*
X73499D03*
X66499D03*
X73499Y1945550D03*
X79500Y1987500D03*
X65499Y1982550D03*
X73499D03*
X82999D03*
X90900Y5800D03*
X90899Y14850D03*
X96999Y49550D03*
X92999Y52050D03*
X97800Y36000D03*
X96900Y40400D03*
X93000Y44900D03*
X92900Y39700D03*
X95814Y136065D03*
X96184Y151065D03*
Y166065D03*
X97999Y199050D03*
X92899Y231450D03*
X86899Y242750D03*
X93199Y279650D03*
X84899Y289250D03*
X90899Y309550D03*
X94199Y325550D03*
X93499Y337450D03*
X89899Y368350D03*
X95499Y355450D03*
X89999Y396450D03*
X87599Y403950D03*
X95399Y416350D03*
X89099Y426150D03*
X99399Y437450D03*
X93500Y445300D03*
X97699Y449850D03*
X93199D03*
X97999Y445550D03*
X94500Y456800D03*
X100500Y456700D03*
X98999Y488050D03*
X94499Y486550D03*
X93499Y477050D03*
X97699Y481550D03*
Y477050D03*
X93499Y481550D03*
X101500Y536500D03*
X93599Y581236D03*
X93100Y571640D03*
X92599Y606236D03*
X98001Y856950D03*
X97800Y851800D03*
X93808Y852063D03*
X94001Y856895D03*
X90000Y854500D03*
X96000Y866000D03*
X97499Y862050D03*
X93299D03*
X93499Y897152D03*
X88999Y882550D03*
X93900Y882400D03*
X97900D03*
X97700Y887400D03*
X93690Y887139D03*
X89499Y892050D03*
X97499Y892550D03*
X93499Y892050D03*
X93000Y907165D03*
X83988Y934028D03*
X86700Y982100D03*
X88005Y996217D03*
X93500Y1000300D03*
X99200Y994200D03*
X100999Y1101050D03*
X104999D03*
X100999Y1096550D03*
X102999Y1188050D03*
X104999Y1231050D03*
X100999Y1231032D03*
X103499Y1305050D03*
X93316Y1351000D03*
X96000Y1369000D03*
X96100Y1384650D03*
X85000Y1536450D03*
X91399Y1549550D03*
X97300Y1564100D03*
X92499Y1589050D03*
X86999D03*
X90999Y1628550D03*
Y1624550D03*
X91121Y1632549D03*
X86299Y1632550D03*
X85999Y1628550D03*
Y1624550D03*
X93999Y1669550D03*
X89999Y1703050D03*
X84099Y1737150D03*
X93499Y1759550D03*
X94336Y1773113D03*
X104417Y1791480D03*
X91499Y1805549D03*
X97999Y1815050D03*
X104500Y1813400D03*
X103920Y1833104D03*
X89200Y1832000D03*
X98999Y1891050D03*
X83999Y1900050D03*
Y1945050D03*
X98433Y1940510D03*
X98999Y1944550D03*
X102433Y1940555D03*
X103433Y1944510D03*
X92499Y1959050D03*
X101699Y1983850D03*
X98000Y1987500D03*
X91499Y1983050D03*
X107000Y6000D03*
X119499Y49550D03*
X116400Y56000D03*
X114800Y68500D03*
X116499Y82050D03*
X116999Y111050D03*
Y96050D03*
X123499Y149050D03*
Y140050D03*
X117500Y162300D03*
X124300Y167800D03*
X109499Y410250D03*
X124899Y409050D03*
X126099Y396150D03*
X111299Y425850D03*
X122499Y427900D03*
X123999Y495050D03*
X108599Y557236D03*
X108900Y587600D03*
X112200Y762200D03*
X112000Y773000D03*
X111299Y821050D03*
X112999Y901150D03*
X106500Y943000D03*
X105300Y960300D03*
X106700Y997800D03*
X109499Y1080550D03*
X111140Y1074659D03*
X105006Y1096866D03*
X120982Y1099733D03*
X109499Y1098350D03*
X110999Y1130550D03*
X115200Y1130300D03*
X110999Y1126050D03*
Y1122050D03*
Y1118050D03*
X114999Y1126050D03*
Y1122050D03*
Y1118050D03*
X106999Y1114960D03*
X120999Y1188050D03*
X111999D03*
X121657Y1224604D03*
X120999Y1228550D03*
X104999Y1265050D03*
X120499Y1264550D03*
X123938Y1267623D03*
X117149Y1267550D03*
X113999Y1285550D03*
X105499Y1292550D03*
X123500Y1360300D03*
X122600Y1565000D03*
X124999Y1616050D03*
Y1620050D03*
Y1629050D03*
Y1633050D03*
X119999Y1629050D03*
X120100Y1633100D03*
X122499Y1668550D03*
Y1672550D03*
X118999Y1670550D03*
X118499Y1697750D03*
X105749Y1712749D03*
X116499Y1716750D03*
X117499Y1745050D03*
X123499Y1747050D03*
X120299Y1796150D03*
X121151Y1805128D03*
X111499Y1877550D03*
Y1882550D03*
X122999Y1883050D03*
X115999Y1882550D03*
X116499Y1877550D03*
X122999Y1889050D03*
X124433Y1908510D03*
X124999Y1912550D03*
X120999Y1930550D03*
X119999Y1978550D03*
X119499Y1972550D03*
X108499Y1981750D03*
X115000Y1987000D03*
X145499Y49050D03*
X129100Y55900D03*
X127499Y65050D03*
X141999Y65550D03*
X129999Y78050D03*
X127999Y99550D03*
X133999Y149050D03*
X142999Y141050D03*
X132999Y141550D03*
X144499Y149050D03*
X131799Y201950D03*
X142688Y218861D03*
X143110Y203861D03*
X133000Y240500D03*
X135399Y277050D03*
X130799Y300250D03*
X130099Y326150D03*
X134699Y356050D03*
X139399Y372350D03*
X127999Y425050D03*
Y421050D03*
Y429550D03*
X144999Y425550D03*
X133499Y445050D03*
X128999Y445550D03*
X130000Y452000D03*
X135999Y472550D03*
X135140Y478930D03*
X139200Y484300D03*
X134499Y488050D03*
X132349Y509050D03*
X145649Y509550D03*
X136349Y509050D03*
X140499Y499050D03*
X136299D03*
X147300Y526700D03*
X134700Y553800D03*
X137100Y570500D03*
X140000Y587700D03*
X140499Y600550D03*
X143999Y605550D03*
X140499Y626050D03*
X131099Y700450D03*
X139099Y707150D03*
X141234Y1029885D03*
X140864Y1044885D03*
X137900Y1103400D03*
X139100Y1097100D03*
X134500Y1108100D03*
X143200Y1116300D03*
X133200Y1132100D03*
X126400Y1138100D03*
X145900Y1163200D03*
X144399Y1171150D03*
X141499Y1185550D03*
X128400Y1188600D03*
X143899Y1196750D03*
X142499Y1205550D03*
X130999Y1198050D03*
X144149Y1230113D03*
Y1226113D03*
Y1222113D03*
X126499Y1264550D03*
X136783Y1335517D03*
X143500Y1323500D03*
X145999Y1353050D03*
X143199Y1412050D03*
X140799Y1435460D03*
X129100Y1564700D03*
X127200Y1569800D03*
X126562Y1670613D03*
X131599Y1714150D03*
X135899Y1722550D03*
X127499Y1708250D03*
X130499Y1730050D03*
X128000Y1735000D03*
X144499Y1729550D03*
X139500Y1730500D03*
X133000Y1734500D03*
X144499Y1745550D03*
X137999Y1747723D03*
X129999Y1747050D03*
X126599Y1789650D03*
X142144Y1801644D03*
X143490Y1855972D03*
X127499Y1889050D03*
X126999Y1882550D03*
X142499Y1905972D03*
X141499Y1895972D03*
X129999Y1908550D03*
X129433Y1912510D03*
X127499Y1978550D03*
X133499D03*
X132999Y1972550D03*
X126999D03*
X146899Y1961750D03*
X146000Y1987500D03*
X128500D03*
X157299Y5150D03*
X167499Y43550D03*
X156499Y66050D03*
X166999Y88050D03*
X166499Y83550D03*
Y79050D03*
X158499D03*
Y84050D03*
Y88550D03*
Y93550D03*
X166999Y92550D03*
X152499Y103550D03*
X165499Y106050D03*
X166999Y97050D03*
X152999Y141050D03*
X167499Y149550D03*
X163499Y140050D03*
X160999Y149550D03*
X156817Y165883D03*
X149400Y162500D03*
X155999Y181050D03*
X166800Y240800D03*
X158999Y259800D03*
X152808Y246341D03*
X157740Y273924D03*
X167299Y369350D03*
X150699Y411050D03*
X152499Y395950D03*
X149700Y471600D03*
X154100Y476500D03*
X164600Y476700D03*
X157499Y502550D03*
X153499D03*
X148999D03*
X147590Y521500D03*
X154099Y529236D03*
X153000Y574000D03*
X160900Y573000D03*
X162500Y623400D03*
X152400Y643300D03*
X152124Y651868D03*
X159054Y665400D03*
X161999Y768050D03*
X152499Y810550D03*
Y816050D03*
Y820550D03*
Y825050D03*
X161999Y843550D03*
Y848050D03*
X156499Y846050D03*
X156999Y850050D03*
X156499Y870550D03*
Y876050D03*
X163999Y863050D03*
X159999D03*
X155999Y859050D03*
Y863050D03*
X158114Y883290D03*
X156499Y886950D03*
X159459Y896616D03*
X163499Y896550D03*
X155499Y891050D03*
Y896050D03*
X157499Y904550D03*
Y909050D03*
X151999Y936550D03*
X152499Y931550D03*
X153299Y943750D03*
X159186Y946117D03*
X156499Y985950D03*
X149499Y997650D03*
X162499Y1023550D03*
X158300Y1015000D03*
X163499Y1035050D03*
X159499Y1044579D03*
X151300Y1049300D03*
X165600Y1057428D03*
X168099Y1083550D03*
X164999Y1075550D03*
X159055Y1070400D03*
X167999Y1092850D03*
X167499Y1118550D03*
X167999Y1130550D03*
X163499Y1171650D03*
X151699Y1158550D03*
X151499Y1173050D03*
X150999Y1181150D03*
X148499Y1222113D03*
Y1226113D03*
X148486Y1230113D03*
X167499Y1389050D03*
X156999Y1397750D03*
X166799Y1409350D03*
X157915Y1420460D03*
X163499Y1433350D03*
X165499Y1453550D03*
X166799Y1487450D03*
X159054Y1476200D03*
X167499Y1714113D03*
X162499D03*
X165499Y1730613D03*
X167999Y1726613D03*
X163499D03*
X157500Y1797400D03*
X158000Y1825400D03*
X157999Y1840972D03*
X167200Y1868000D03*
X159054Y1855050D03*
X163599Y1892050D03*
X168299Y1879850D03*
X159054Y1881800D03*
X159173Y1935972D03*
X148499Y1977250D03*
X163500Y1987500D03*
X189499Y4550D03*
Y39150D03*
X172999Y52050D03*
X183499Y45550D03*
X168499Y65550D03*
X178999Y88550D03*
X169999Y103050D03*
X176499Y140050D03*
X177899Y199250D03*
X185999Y250550D03*
X181299Y267350D03*
X187199Y359050D03*
X181599Y396250D03*
X168999Y413050D03*
X188499Y413550D03*
X179999Y442550D03*
X179649Y438550D03*
X183999D03*
Y442550D03*
Y447050D03*
X179999D03*
X171300Y476700D03*
X184200Y484400D03*
X187499Y531613D03*
Y536113D03*
X188999Y541113D03*
Y549613D03*
Y545613D03*
X181999Y624050D03*
Y609550D03*
Y641550D03*
X182599Y688350D03*
X171999Y672450D03*
X170799Y689150D03*
X178899Y765250D03*
X172599Y774250D03*
X168499Y846713D03*
X173899Y846550D03*
X172099Y877450D03*
X169299Y956350D03*
X171499Y998650D03*
X169299Y1067150D03*
X171599Y1139950D03*
X180400Y1202800D03*
X181700Y1219900D03*
X179800Y1244100D03*
X179500Y1262000D03*
X175823Y1297070D03*
X179999Y1301550D03*
Y1292550D03*
X175499D03*
X179999Y1296613D03*
X175499Y1302113D03*
X179999Y1306050D03*
X175499Y1306113D03*
X181000Y1361000D03*
X180400Y1374000D03*
X178200Y1393400D03*
X180599Y1424050D03*
X180000Y1439500D03*
X176599Y1447450D03*
X172299Y1465850D03*
X181500Y1479000D03*
X176299Y1500150D03*
X180299Y1626550D03*
X180000Y1619600D03*
X180299Y1634550D03*
X179733Y1630590D03*
X181900Y1675300D03*
X180701Y1716050D03*
X179701Y1724550D03*
X172499Y1714050D03*
X180000Y1731000D03*
X170499Y1731050D03*
X172499Y1726613D03*
X185999Y1746050D03*
X182299Y1801350D03*
X173899Y1813250D03*
X177599Y1866750D03*
X168499Y1855550D03*
X181099Y1885850D03*
X168699Y1957150D03*
X183999Y1968150D03*
X188199Y1978250D03*
X183000Y1987500D03*
X206999Y5050D03*
X197999Y39900D03*
X193999D03*
X208499Y45650D03*
X199999Y46050D03*
X194499Y44050D03*
X191999Y68050D03*
X192499Y57550D03*
X195499Y99050D03*
X204499Y116550D03*
X194499Y109350D03*
X206899Y171650D03*
X190199Y178650D03*
X191999Y221550D03*
X203499Y250550D03*
X201199Y266750D03*
X209199Y365050D03*
X209499Y412550D03*
X209999Y426150D03*
X194999Y490050D03*
X190499Y487550D03*
X191199Y491550D03*
X205300Y508100D03*
X190499Y507513D03*
X193499Y541113D03*
Y549613D03*
X193999Y545550D03*
X206499Y623550D03*
Y609050D03*
X207300Y639400D03*
X199199Y659150D03*
X190399Y689050D03*
X209500Y759000D03*
X208799Y766750D03*
X190699Y778350D03*
X197099Y795050D03*
X208299Y805350D03*
X202900Y811900D03*
X198199Y805950D03*
X204496Y846111D03*
X204649Y838050D03*
X208999D03*
X209000Y846113D03*
X204649Y842113D03*
X208986D03*
X198499Y884113D03*
X204699Y896610D03*
Y929450D03*
X206699Y953050D03*
X203999Y943350D03*
X205999Y978250D03*
X206299Y990250D03*
X207299Y1008150D03*
X202100Y1028100D03*
X199499Y1093850D03*
X209900Y1093600D03*
X208199Y1145850D03*
X210199Y1173450D03*
X204199Y1163850D03*
X201600Y1205900D03*
X196499Y1215550D03*
Y1196550D03*
X196399Y1236650D03*
X196499Y1224550D03*
X195499Y1251050D03*
X202199Y1276850D03*
X195499Y1279050D03*
Y1270050D03*
X202899Y1291450D03*
X207699Y1337950D03*
X195500Y1352500D03*
X208049Y1385550D03*
X203199Y1393250D03*
X204699Y1418350D03*
X201000Y1408500D03*
X194200Y1457900D03*
X204999Y1472650D03*
X208999Y1491250D03*
X202399Y1500750D03*
X195700Y1619100D03*
X195600Y1623700D03*
X209200Y1624000D03*
X200600Y1663600D03*
X199900Y1670600D03*
X193499Y1674050D03*
X197600Y1694900D03*
X204400Y1688200D03*
X209901Y1691850D03*
X201801Y1701450D03*
X195001Y1708150D03*
X205200Y1708000D03*
X195500Y1717000D03*
X195000Y1725500D03*
X206900Y1726700D03*
X199699Y1761450D03*
X205199Y1801950D03*
X209999Y1825050D03*
X192100Y1813500D03*
X195499Y1852550D03*
X204399Y1855450D03*
X206999Y1867550D03*
X207199Y1892850D03*
X191599Y1891550D03*
X199599Y1879850D03*
X205499Y1968650D03*
X190199Y1957650D03*
X199600Y1974900D03*
X209699Y1978750D03*
X199000Y1987500D03*
X226499Y5050D03*
X227999Y38050D03*
X225499Y52550D03*
Y46550D03*
Y63550D03*
Y58050D03*
X229099Y161350D03*
X227999Y178050D03*
X227499Y192050D03*
X227999Y187050D03*
Y182550D03*
X210999Y221550D03*
X217999Y250550D03*
X223799Y365350D03*
X217599Y396450D03*
X218499Y474850D03*
X224299Y494650D03*
X220499Y560050D03*
Y545550D03*
Y577550D03*
X224999Y613450D03*
X219999Y632550D03*
Y647050D03*
X226399Y677550D03*
X212999Y677350D03*
X218800Y668700D03*
X224099Y770250D03*
X214799Y774750D03*
X227199Y795050D03*
X217300Y816800D03*
X215999Y887550D03*
X220499D03*
X215499Y883550D03*
X215500Y893610D03*
X219499Y939613D03*
X214999D03*
X219499Y926613D03*
X214999D03*
X225299Y957650D03*
X213999Y958650D03*
X219499Y948613D03*
Y943813D03*
X214999Y944113D03*
Y948613D03*
X217499Y981050D03*
X216999Y967550D03*
X217499Y998550D03*
X217999Y1012050D03*
X215999Y1039550D03*
X216499Y1053050D03*
X229800Y1077300D03*
X214499Y1154250D03*
X223099Y1182750D03*
X212499Y1184550D03*
Y1212550D03*
X221599Y1237250D03*
X220999Y1224350D03*
X222299Y1251850D03*
X229899Y1250550D03*
X211499Y1258050D03*
Y1239050D03*
X216300Y1274800D03*
X211499Y1267050D03*
X219099Y1325950D03*
X226599Y1340250D03*
X213199Y1350050D03*
X227399Y1363050D03*
X217499Y1387450D03*
X230599Y1400250D03*
X217999Y1408850D03*
X227999Y1421550D03*
X226300Y1447800D03*
X230899Y1437350D03*
X212400Y1433700D03*
X223029Y1465580D03*
X213399Y1500300D03*
X212899Y1535550D03*
X230999D03*
X221199Y1556050D03*
X211999Y1568550D03*
X231499Y1575050D03*
X224499D03*
X217999Y1574550D03*
X211999D03*
X225499Y1606050D03*
X218000Y1614300D03*
X228999Y1637550D03*
X211999Y1653550D03*
X230600Y1670500D03*
X213000Y1672500D03*
X216601Y1684350D03*
X226800Y1684200D03*
X220100Y1691700D03*
X212000Y1701300D03*
X222700Y1710100D03*
X222499Y1743850D03*
X221499Y1760950D03*
X220799Y1791550D03*
X215299Y1813950D03*
X224800Y1867000D03*
X228999Y1856050D03*
X229800Y1872000D03*
X212399Y1885850D03*
X218100Y1882700D03*
X214999Y1914050D03*
X215999Y1955050D03*
X210999Y1945750D03*
X226999Y1941050D03*
X227499Y1971050D03*
X221300Y1971200D03*
X225199Y1978750D03*
X216999Y1987550D03*
X241999Y5050D03*
X247499Y37550D03*
X246999Y46550D03*
Y56050D03*
X247499Y65050D03*
X241099Y95050D03*
X244499Y136550D03*
Y122050D03*
X244900Y149100D03*
X231999Y178050D03*
Y192050D03*
Y187050D03*
Y182550D03*
X232400Y220700D03*
X249800Y248800D03*
X235399Y263350D03*
X237699Y426050D03*
X232999Y414550D03*
X252499Y415050D03*
X251499Y446050D03*
X231999Y445550D03*
X251999Y462050D03*
X232499Y461550D03*
X244199Y483350D03*
X242099Y511750D03*
X244999Y559550D03*
Y545050D03*
Y577050D03*
X244499Y632050D03*
X246500Y663300D03*
X245000Y647000D03*
X234200Y668300D03*
X245599Y773450D03*
X234299Y773750D03*
X247099Y795050D03*
X233799Y806350D03*
X245399Y823550D03*
X244099Y857450D03*
X252399Y838250D03*
X245199Y878050D03*
X232399Y886550D03*
X252899Y886350D03*
X245399Y907450D03*
X243899Y923650D03*
X242199Y938750D03*
X252499Y948850D03*
X244199Y973250D03*
X232299Y981950D03*
X233499Y966050D03*
X245899Y995250D03*
X233999Y997050D03*
Y1012550D03*
X232499Y1038050D03*
X242000Y1069700D03*
X249499Y1104150D03*
X232599Y1195750D03*
X251999Y1184550D03*
X242199Y1210050D03*
X242599Y1198350D03*
X247899Y1208650D03*
X234299Y1232650D03*
X250900Y1248500D03*
X242900Y1263000D03*
X232799Y1276150D03*
X241399Y1303250D03*
X239099Y1314150D03*
X252399Y1326350D03*
X245999Y1339050D03*
Y1358050D03*
X234300Y1375700D03*
X246499Y1370050D03*
X249800Y1388400D03*
X244999Y1412550D03*
X245499Y1424550D03*
X238899Y1453750D03*
X248000Y1482000D03*
X250199Y1473550D03*
X247500Y1499000D03*
X236999Y1535550D03*
X238300Y1575100D03*
X246200Y1617600D03*
X239400Y1624300D03*
X242999Y1658050D03*
X237400Y1663800D03*
X235499Y1697050D03*
X249199Y1743150D03*
X237999Y1730550D03*
X244999Y1755050D03*
X252199Y1793050D03*
X238699Y1801850D03*
X247252Y1826803D03*
X241199Y1867150D03*
X244700Y1878700D03*
X241255Y1896055D03*
X231999Y1918050D03*
X249499Y1924350D03*
X238999Y1970550D03*
X232999Y1971050D03*
X240900Y1979000D03*
X236500Y1987500D03*
X261499Y4550D03*
X253999Y48050D03*
X264999Y55350D03*
X261299Y75950D03*
X258699Y104550D03*
X265299Y96250D03*
X262299Y164050D03*
X262699Y208550D03*
X271999Y216050D03*
X265999Y245050D03*
X267498Y305114D03*
Y300114D03*
Y295114D03*
Y310114D03*
X258999Y396650D03*
X266699Y425050D03*
X269999Y415050D03*
X272499Y445050D03*
X266199Y472350D03*
X272999Y461050D03*
X257499Y498050D03*
Y512550D03*
Y530050D03*
X256499Y577050D03*
Y591550D03*
Y609050D03*
X269499Y616550D03*
X257199Y640050D03*
X269499Y631050D03*
Y648550D03*
X268499Y701550D03*
Y706550D03*
Y716550D03*
Y711550D03*
X268099Y795450D03*
X254699Y807650D03*
X264499Y829050D03*
X264999Y842550D03*
Y858450D03*
X265799Y901850D03*
X256199Y916250D03*
X254899Y929250D03*
X253499Y938050D03*
X269599Y923950D03*
X267199Y935350D03*
X264799Y946850D03*
X263299Y959350D03*
X272999Y981050D03*
Y965550D03*
X256499Y967050D03*
X262499Y995850D03*
X254499Y984550D03*
X258999Y1011550D03*
X269999Y1037050D03*
X253499Y1038550D03*
X269999Y1052550D03*
X253999Y1052050D03*
X272999Y1102850D03*
X262499Y1129150D03*
X260349Y1139200D03*
X272499Y1153050D03*
X268499D03*
X263999D03*
X259999Y1152992D03*
X271999Y1161550D03*
X267999D03*
X263499D03*
X259499D03*
X272999Y1214150D03*
X261199Y1227950D03*
X264800Y1261300D03*
X254899Y1289950D03*
X264799Y1313850D03*
X265299Y1339650D03*
X263699Y1359550D03*
X265499Y1376950D03*
X258999Y1396950D03*
X270599Y1408550D03*
X259299Y1438750D03*
X268499Y1453550D03*
X260999Y1503550D03*
X266999Y1512550D03*
X267349Y1518150D03*
Y1522550D03*
Y1527172D03*
X265700Y1635100D03*
X258700Y1645100D03*
X270999Y1660550D03*
X253999Y1676550D03*
X273499Y1694050D03*
X255699Y1722550D03*
X256499Y1710050D03*
X263499Y1734550D03*
X270599Y1748950D03*
X259499Y1760650D03*
X270599Y1801450D03*
X253899Y1813250D03*
X261499Y1825050D03*
X255999Y1855950D03*
X270299Y1867250D03*
X266999Y1915550D03*
Y1920050D03*
Y1924550D03*
Y1929050D03*
Y1933550D03*
X264499Y1968050D03*
X254500Y1987500D03*
X272000D03*
X278999Y5050D03*
X292999Y4550D03*
X294100Y28000D03*
X289499Y39050D03*
X286603Y34928D03*
X285999Y72550D03*
X289999D03*
X290999Y67550D03*
X288499Y76550D03*
X289499Y80550D03*
X283599Y106250D03*
X274700Y131500D03*
X280999Y120050D03*
Y152050D03*
X290999Y216050D03*
X283499Y245050D03*
X279998Y304114D03*
Y299614D03*
Y295114D03*
Y308614D03*
X284999Y342750D03*
X277799Y338599D03*
X280345Y328896D03*
X293998Y361114D03*
Y356614D03*
Y352114D03*
X289998Y361114D03*
Y356614D03*
Y352114D03*
X276299Y376050D03*
X289399Y395750D03*
X284499Y415050D03*
X291599Y446150D03*
X286999Y462050D03*
X281999Y497550D03*
X292999Y483550D03*
X281999Y512050D03*
Y529550D03*
X277999Y545350D03*
X280999Y576550D03*
Y591050D03*
Y608550D03*
X293999Y616050D03*
Y630550D03*
Y648050D03*
X280999Y701550D03*
Y705550D03*
Y717550D03*
X280433Y713590D03*
X285264Y749050D03*
X284764Y738315D03*
X294999Y767050D03*
X290999D03*
X294999Y762550D03*
Y758050D03*
X290999Y762550D03*
Y758050D03*
X287799Y794850D03*
X275299Y806350D03*
X288899Y820550D03*
X280999Y827550D03*
X283599Y857450D03*
X293899Y843850D03*
X280999Y843050D03*
Y870050D03*
X281499Y883550D03*
X274299Y912950D03*
X287299Y901050D03*
X281099Y943550D03*
X278799Y956150D03*
X290099Y948650D03*
X289399Y963350D03*
X277599Y975250D03*
X288099Y971250D03*
X285399Y982950D03*
X294699Y989550D03*
X287099Y1000150D03*
X274999Y996550D03*
X289699Y1021750D03*
X275099Y1024750D03*
X274999Y1012050D03*
X287099Y1035050D03*
X282999Y1099550D03*
X274900Y1115600D03*
X290699Y1122650D03*
X283499Y1113050D03*
X276299Y1134550D03*
X283299Y1144850D03*
X291399Y1174150D03*
X279799Y1191750D03*
X286599Y1203750D03*
X283799Y1249250D03*
X274299Y1276450D03*
X281099Y1302850D03*
X286799Y1326450D03*
X286499Y1364050D03*
Y1345050D03*
X278799Y1386250D03*
X285499Y1399550D03*
X278000Y1422000D03*
X285499Y1418550D03*
Y1427550D03*
X286600Y1449700D03*
X279499Y1510550D03*
X286700Y1516100D03*
X279499Y1515050D03*
X279075Y1525957D03*
X278567Y1529925D03*
X290411Y1546462D03*
X286868Y1557582D03*
X293998Y1573614D03*
Y1569114D03*
X289998Y1573614D03*
Y1569114D03*
X293998Y1578114D03*
X289998D03*
X278499Y1621550D03*
X289000Y1641800D03*
X284300Y1676900D03*
X291099Y1707450D03*
X280499Y1718550D03*
X285499Y1742550D03*
X290699Y1760750D03*
X286599Y1791850D03*
X284299Y1811150D03*
X295299Y1870250D03*
X283999Y1856050D03*
X293999Y1933050D03*
X281999Y1918550D03*
Y1923550D03*
Y1928550D03*
X293999Y1971050D03*
Y1966550D03*
Y1962050D03*
X289499Y1961550D03*
Y1966550D03*
Y1971050D03*
X291499Y1987550D03*
X310499Y5050D03*
X304800Y29200D03*
X304500Y44500D03*
X303300Y39500D03*
X308700Y39800D03*
X308800Y46400D03*
X306999Y55450D03*
X311299D03*
X315799Y55350D03*
X312499Y72550D03*
X308499D03*
X303999Y74050D03*
X307999Y78550D03*
X315800Y104200D03*
X306100Y126500D03*
X307199Y205550D03*
X310499Y216550D03*
X297999Y245050D03*
X313199Y270350D03*
X313000Y313900D03*
X305998Y352114D03*
X299899Y376650D03*
X310999Y396250D03*
X300899Y431850D03*
X303999Y415550D03*
X306100Y462000D03*
X312499Y484050D03*
X298599Y501250D03*
X309399Y513450D03*
X297599Y519350D03*
X307499Y555550D03*
Y541050D03*
X297499Y551050D03*
X296199Y568550D03*
X307499Y573050D03*
X302899Y607950D03*
X307499Y661550D03*
Y647050D03*
X297699Y681850D03*
X307499Y679050D03*
X308899Y705150D03*
X298399Y703450D03*
X296399Y716950D03*
X306999Y758050D03*
X314499Y754550D03*
X307999Y803150D03*
X307899Y794550D03*
X300199Y835250D03*
X304899Y856150D03*
X313499Y847850D03*
X315199Y869450D03*
X297499Y868550D03*
X302499Y899050D03*
X297499Y884050D03*
X302199Y914650D03*
X315199Y925950D03*
X295999Y948550D03*
X310699Y943550D03*
X299399Y965950D03*
X298099Y977250D03*
X307999Y970650D03*
X306699Y981250D03*
X304399Y997550D03*
X298399Y1008150D03*
X306399Y1020750D03*
X303699Y1038050D03*
X299999Y1052350D03*
X304699Y1057050D03*
X312299Y1093550D03*
X299499Y1098050D03*
Y1113550D03*
X316499Y1124550D03*
X307999Y1142050D03*
X304499Y1156650D03*
X313499Y1170150D03*
X300699Y1185150D03*
X315408Y1202663D03*
X311999Y1213850D03*
X300699Y1227350D03*
X310299Y1240050D03*
X304699Y1265850D03*
X312499Y1280350D03*
X295399Y1292950D03*
X300499Y1305350D03*
X311500Y1316300D03*
X297899Y1336150D03*
X298099Y1357250D03*
X311900Y1344900D03*
X301699Y1377950D03*
X312900Y1366900D03*
X301699Y1395750D03*
X313600Y1391300D03*
X303499Y1411250D03*
X312100Y1420700D03*
X300899Y1433350D03*
X313600Y1442700D03*
X304699Y1457550D03*
X312800Y1467400D03*
X296599Y1497150D03*
X312000Y1514600D03*
X305998Y1569114D03*
X307000Y1619600D03*
X302399Y1662950D03*
X299999Y1696050D03*
X303999Y1722050D03*
X297099Y1733850D03*
X303499Y1753550D03*
X303999Y1800850D03*
X299995Y1810554D03*
X315499Y1812250D03*
X298999Y1855950D03*
X313599Y1870250D03*
X308099Y1880550D03*
X313599Y1889250D03*
X314099Y1901250D03*
X305999Y1913050D03*
X306999Y1932550D03*
X302499D03*
X298499D03*
X302499Y1922050D03*
X296858Y1956228D03*
X305999Y1964050D03*
Y1969550D03*
X311500Y1987500D03*
X329999Y5050D03*
X332200Y94200D03*
X324800Y93100D03*
X321799Y173950D03*
X317499Y192950D03*
X331499Y193250D03*
X325499Y249450D03*
X337499Y282550D03*
X316999Y312576D03*
X323499Y331550D03*
X321748Y343299D03*
X328799Y372350D03*
X336099Y417550D03*
X322099Y426850D03*
X324999Y414550D03*
X328599Y442250D03*
X327900Y463200D03*
X333499Y483050D03*
X329999Y510450D03*
X321999Y533150D03*
X331999Y555050D03*
Y540550D03*
X321999Y550550D03*
X321299Y565250D03*
X320799Y582050D03*
X331999Y572550D03*
X328599Y602450D03*
X328499Y635650D03*
X317999Y627850D03*
X331999Y661050D03*
Y646550D03*
Y678550D03*
X324599Y696150D03*
X330799Y712450D03*
X331263Y742294D03*
X318999Y814350D03*
X325599Y823950D03*
X330299Y871850D03*
X323799Y859850D03*
X321099Y899650D03*
X323099Y885050D03*
X322099Y913650D03*
X331099Y923650D03*
X328099Y937250D03*
X323499Y956950D03*
X329799Y970650D03*
X333099Y983450D03*
X320999Y997250D03*
X331299Y1017150D03*
X321299Y1012450D03*
Y1024750D03*
X331599Y1028750D03*
X329599Y1040750D03*
X318299Y1038750D03*
X329599Y1057050D03*
X319999Y1066950D03*
X317699Y1054650D03*
X329299Y1098550D03*
X326599Y1112350D03*
X332999Y1123050D03*
X323999Y1153250D03*
X332999Y1138550D03*
X317999Y1137550D03*
X329799Y1182750D03*
X328999Y1200550D03*
X326649Y1227850D03*
Y1218850D03*
X327999Y1255050D03*
X333349Y1270500D03*
Y1288900D03*
Y1307000D03*
Y1332800D03*
Y1363500D03*
Y1393100D03*
Y1429500D03*
Y1481900D03*
X332500Y1519700D03*
X337199Y1636350D03*
X320299Y1642950D03*
X316799Y1657450D03*
X335767Y1662735D03*
X318499Y1675550D03*
X334399Y1691650D03*
X329999Y1716950D03*
X320999Y1706050D03*
X321999Y1733050D03*
X326301Y1766030D03*
X321499Y1772550D03*
X327299Y1791850D03*
X322299Y1802150D03*
X334999Y1797050D03*
X337499Y1855950D03*
X316999D03*
X336799Y1869950D03*
X326399Y1876250D03*
X336799Y1888950D03*
X326899Y1907250D03*
X326399Y1895250D03*
X336799Y1897950D03*
X335799Y1916450D03*
X331499Y1940750D03*
X326799Y1977050D03*
X329999Y1987550D03*
X345499Y5050D03*
X347328Y31519D03*
X337799Y67110D03*
X356499Y113050D03*
X351999D03*
X347499D03*
X355999Y100550D03*
X350999D03*
X345999D03*
X338499Y120550D03*
X342999Y169050D03*
X354099Y175350D03*
X343399Y161350D03*
X343999Y190050D03*
X343799Y204550D03*
X355499Y219050D03*
X337999D03*
X355999Y242750D03*
X343499Y253550D03*
X347699Y269050D03*
X354999Y282550D03*
X347399Y301950D03*
X339399Y358050D03*
X357999Y359050D03*
X354099Y373050D03*
X338399Y395650D03*
X338899Y433850D03*
X354699Y426650D03*
X356399Y451750D03*
X351399Y470750D03*
X340799Y512050D03*
X358399Y498650D03*
X341399Y535850D03*
X357399Y521250D03*
Y530550D03*
X341399Y558950D03*
X357399Y543850D03*
X357999Y559450D03*
X340299Y586550D03*
X342199Y613050D03*
X342099Y646350D03*
X341899Y664950D03*
X342599Y678850D03*
X345399Y698950D03*
X357699Y707750D03*
X341399Y715050D03*
X355999Y752850D03*
X353999Y787750D03*
X347699Y773450D03*
X338099Y811650D03*
X338599Y821650D03*
Y840450D03*
X340099Y887350D03*
X338399Y901050D03*
X340099Y910350D03*
X340399Y931250D03*
X340099Y952850D03*
X339599Y1081550D03*
X344399Y1338150D03*
X343599Y1360050D03*
X344099Y1393750D03*
Y1421150D03*
Y1449550D03*
X351899Y1570850D03*
X344500Y1583600D03*
X350600Y1610900D03*
X349099Y1634550D03*
X351099Y1691150D03*
X352000Y1700400D03*
X343899Y1752650D03*
X357999Y1796050D03*
X355699Y1810750D03*
X351999Y1855450D03*
X348999Y1879050D03*
X349499Y1910050D03*
X348999Y1898050D03*
X347999Y1925550D03*
X348499Y1956550D03*
X347999Y1944550D03*
X347699Y1972250D03*
X345499Y1987550D03*
X364999Y4550D03*
X371999Y15550D03*
X376499D03*
X369999Y23550D03*
Y19050D03*
X378428Y51119D03*
X376999Y65550D03*
Y70050D03*
X360999Y113050D03*
Y100550D03*
X363999Y136050D03*
Y121550D03*
Y153550D03*
X362999Y190050D03*
X369999Y219050D03*
X362499Y253550D03*
X369499Y282550D03*
X359399Y307250D03*
X368299Y386350D03*
X359399Y576050D03*
Y599650D03*
X360399Y615550D03*
X359699Y627550D03*
X358899Y657150D03*
X359399Y669450D03*
X359199Y690650D03*
X377499Y1182050D03*
Y1210050D03*
Y1201050D03*
X376499Y1236550D03*
Y1255550D03*
Y1264550D03*
X376599Y1293950D03*
X375599Y1323350D03*
X374499Y1347550D03*
Y1375550D03*
Y1366550D03*
X373499Y1402050D03*
Y1421050D03*
X376299Y1437650D03*
X373499Y1430050D03*
X373099Y1456550D03*
X374799Y1491250D03*
X374099Y1554550D03*
X376099Y1572850D03*
X375099Y1608250D03*
X377700Y1629000D03*
X374999Y1656750D03*
X377099Y1696350D03*
X359499Y1736850D03*
X376799Y1734050D03*
X376499Y1775550D03*
X369499Y1855950D03*
X359999Y1878550D03*
X369799Y1880050D03*
X359999Y1897550D03*
Y1906550D03*
X369999Y1901950D03*
X358999Y1925050D03*
X369199Y1919750D03*
X367299Y1956950D03*
X367999Y1940250D03*
X367299Y1972950D03*
X364999Y1987050D03*
X382499Y5050D03*
X395999Y5550D03*
X380999Y15550D03*
X382499Y20050D03*
X381499Y65550D03*
Y70050D03*
X385499Y59550D03*
X390411Y69638D03*
X389599Y90950D03*
X380599Y103550D03*
X381299Y136750D03*
X400499Y134050D03*
Y119550D03*
Y151550D03*
X389299Y161650D03*
X382499Y190550D03*
X387599Y220150D03*
X385999Y207250D03*
X381999Y254050D03*
X382999Y276650D03*
X386899Y299250D03*
X383299Y310250D03*
X392999Y337050D03*
X386599Y348450D03*
X394899Y357750D03*
X380599Y381050D03*
X380999Y1618050D03*
X380099Y1709650D03*
X393499Y1759550D03*
X393999Y1784550D03*
X387899Y1802850D03*
X391499Y1855950D03*
X389499Y1885050D03*
Y1913050D03*
Y1904050D03*
X388499Y1932950D03*
Y1950550D03*
X385099Y1975950D03*
X399299Y1976750D03*
X388499Y1959550D03*
X382499Y1987550D03*
X413499Y6050D03*
X416999Y25050D03*
X417499Y46550D03*
X416999Y63550D03*
X417499Y79050D03*
Y93550D03*
Y108050D03*
Y125550D03*
X416999Y145050D03*
Y164050D03*
X417999Y185050D03*
X412999Y275550D03*
Y307550D03*
Y290050D03*
X422199Y363350D03*
X420199Y391350D03*
X415099Y422550D03*
X410799Y431150D03*
X419599Y458550D03*
X415999Y518550D03*
X420199Y638550D03*
X418799Y877050D03*
Y896050D03*
X409499Y1102550D03*
X419999Y1115550D03*
X415499Y1161550D03*
X416099Y1183550D03*
X415499Y1176050D03*
X419499Y1234050D03*
Y1219550D03*
X420099Y1241550D03*
X420499Y1335550D03*
X416699Y1342650D03*
X416199Y1367550D03*
X414799Y1532350D03*
X418299Y1561250D03*
X415999Y1603250D03*
X416199Y1625250D03*
X414799Y1653750D03*
X414399Y1678350D03*
X414499Y1707250D03*
X410757Y1772872D03*
X417799Y1790850D03*
X414499Y1810450D03*
X406999Y1855950D03*
X421399Y1888050D03*
X406499Y1893050D03*
Y1874050D03*
X421399Y1907050D03*
X406999Y1905050D03*
X420399Y1934550D03*
X421399Y1916050D03*
X405499Y1920550D03*
X420399Y1953550D03*
X405999Y1951550D03*
X405499Y1939550D03*
X420399Y1962550D03*
X420799Y1977250D03*
X420500Y1987000D03*
X403500D03*
X432999Y6050D03*
X436499Y31350D03*
Y50350D03*
X437499Y71350D03*
X441799Y102450D03*
Y121450D03*
X442799Y142450D03*
X430499Y217050D03*
X423799Y259750D03*
X437499Y275050D03*
Y307050D03*
Y289550D03*
X422499Y348150D03*
X438999Y381550D03*
X426599Y415350D03*
X443199Y440850D03*
X440099Y459250D03*
X431099Y479350D03*
X435499Y519050D03*
X430099Y551450D03*
X427999Y580050D03*
Y565550D03*
Y597550D03*
X427499Y624550D03*
X437299Y744650D03*
X435299Y763150D03*
X424999Y766550D03*
X435299Y777650D03*
X422999Y785050D03*
X434799Y814650D03*
X435299Y795150D03*
X422999Y799550D03*
X434799Y833650D03*
X422999Y817050D03*
X422499Y855550D03*
Y836550D03*
X442599Y905650D03*
Y924650D03*
X423299Y994050D03*
Y1013050D03*
X424299Y1034050D03*
X432599Y1064550D03*
X433599Y1085550D03*
X428999Y1102550D03*
X439499Y1115550D03*
X436999Y1128050D03*
X437599Y1150050D03*
X436999Y1142550D03*
X443199Y1224250D03*
Y1238750D03*
X424999Y1278550D03*
Y1259550D03*
X425499Y1290550D03*
X428499Y1325350D03*
X434499Y1360250D03*
X422299Y1394950D03*
X441499Y1399550D03*
X426799Y1416050D03*
X441499Y1414050D03*
X423299Y1430350D03*
X425799Y1447950D03*
X441499Y1431550D03*
X427099Y1469150D03*
X424299Y1541350D03*
X439599Y1552150D03*
X434500Y1579500D03*
X432499Y1617550D03*
X431999Y1605550D03*
X425499Y1635050D03*
X432400Y1680100D03*
X427499Y1662050D03*
X428600Y1691200D03*
X435300Y1715300D03*
X429499Y1748050D03*
X441499Y1758050D03*
X436799Y1772550D03*
X422999Y1778550D03*
X436499Y1836550D03*
X426499Y1855450D03*
X434299Y1876050D03*
Y1904050D03*
Y1895050D03*
X433299Y1922550D03*
Y1950550D03*
Y1941550D03*
X436299Y1977250D03*
X438999Y1987550D03*
X448499Y6050D03*
X463499Y29550D03*
X445799Y165650D03*
Y184650D03*
X446799Y205650D03*
X449999Y217050D03*
X448999Y255550D03*
X444499Y283050D03*
X463999Y283550D03*
X443499Y354050D03*
X464499Y353050D03*
X458499Y382050D03*
X450300Y404200D03*
X453999Y417550D03*
X454999Y438550D03*
X454499Y472550D03*
Y458050D03*
Y490050D03*
X456499Y518050D03*
X453999Y509550D03*
X452499Y579550D03*
Y565050D03*
Y597050D03*
X463999Y659550D03*
X450399Y672750D03*
X444799Y687350D03*
X463999Y674050D03*
Y691550D03*
X451099Y711650D03*
X452099Y762450D03*
Y781450D03*
X453399Y807950D03*
X460999Y819550D03*
X453399Y826950D03*
X462999Y865050D03*
Y884050D03*
X464499Y896050D03*
X462499Y914550D03*
Y929050D03*
X443599Y945650D03*
X462499Y946550D03*
X461999Y966050D03*
Y985050D03*
X462499Y1043850D03*
Y1062850D03*
X463499Y1083850D03*
X463999Y1102050D03*
X444499Y1102550D03*
X454999Y1115550D03*
X453499Y1140550D03*
X454499Y1161550D03*
X443799Y1246250D03*
Y1274250D03*
Y1265250D03*
X448099Y1341250D03*
X444899Y1377950D03*
X464199Y1401450D03*
X459999Y1424050D03*
X456399Y1445950D03*
X459699Y1468050D03*
X445099Y1464250D03*
X444299Y1532650D03*
X461399Y1541650D03*
X452199Y1550650D03*
X449199Y1579050D03*
X443799Y1612250D03*
X460199Y1632850D03*
X449599Y1656950D03*
X448399Y1699450D03*
X447699Y1682850D03*
X458499Y1742050D03*
X463999Y1772050D03*
X445499Y1792550D03*
X448099Y1809450D03*
X443999Y1855950D03*
X460299Y1892350D03*
X446999Y1880050D03*
X460299Y1911350D03*
X446999Y1908050D03*
Y1899050D03*
X460299Y1920350D03*
X445999Y1926550D03*
X459299Y1938850D03*
X445999Y1954550D03*
Y1945550D03*
X459299Y1966850D03*
Y1957850D03*
X455799Y1976750D03*
X456500Y1987500D03*
X467999Y5550D03*
X485499Y6050D03*
X465799Y24750D03*
Y43750D03*
X466799Y64750D03*
X470399Y84550D03*
Y103550D03*
X471399Y124550D03*
X473099Y141050D03*
X483599Y179350D03*
X473099Y160050D03*
X474099Y181050D03*
X472999Y214550D03*
X469999Y254550D03*
X481499Y283550D03*
X466399Y304950D03*
X479299Y297250D03*
X483499Y353050D03*
X485000Y373200D03*
X484900Y394700D03*
X468799Y414250D03*
X472499Y458050D03*
X471499Y493950D03*
X485299Y534550D03*
X479999Y581050D03*
Y566550D03*
Y598550D03*
X472999Y736550D03*
X467699Y772750D03*
X468699Y788350D03*
X479599Y847550D03*
X475699Y880450D03*
X483499Y1064850D03*
X484499Y1085850D03*
X481499Y1102550D03*
X474499Y1115050D03*
X473099Y1144550D03*
X474099Y1165550D03*
X465499Y1265550D03*
Y1284550D03*
Y1293550D03*
X468999Y1323950D03*
X473999Y1342450D03*
X468699Y1362850D03*
X485599Y1367550D03*
X466699Y1378150D03*
X481499Y1402550D03*
Y1417050D03*
X482599Y1449950D03*
X478299Y1464850D03*
X466999Y1530650D03*
X474299Y1544750D03*
X472299Y1572050D03*
X484200Y1579900D03*
X465999Y1603450D03*
X472499Y1611550D03*
X484999Y1636550D03*
X472499Y1620550D03*
X483599Y1662550D03*
X467999Y1668050D03*
X485599Y1694850D03*
X467999Y1687050D03*
Y1696050D03*
X468499Y1712550D03*
X480999Y1756050D03*
X484999Y1779050D03*
X472699Y1792150D03*
X481299Y1811150D03*
X480499Y1855450D03*
X464999D03*
X476199Y1877450D03*
Y1905450D03*
Y1896450D03*
X475199Y1923950D03*
Y1951950D03*
Y1942950D03*
X473299Y1977250D03*
X476000Y1987000D03*
X498999Y6050D03*
X499999Y25550D03*
X500499Y47050D03*
X499999Y64050D03*
X500499Y79550D03*
Y94050D03*
Y108550D03*
Y126050D03*
X499999Y145550D03*
Y164550D03*
X504199Y193250D03*
X502899Y217150D03*
X488999Y254550D03*
X495999Y283550D03*
X502999Y353550D03*
X490999Y412550D03*
X503699Y419250D03*
X490999Y427050D03*
Y444550D03*
X498399Y470050D03*
X490499Y464050D03*
Y483050D03*
X491499Y504050D03*
X504499Y580550D03*
Y566050D03*
Y598050D03*
X488499Y659050D03*
Y673550D03*
Y691050D03*
X506599Y711650D03*
X487299Y716950D03*
X490299Y734550D03*
X489599Y752450D03*
X495999Y795050D03*
X493999Y813550D03*
Y828050D03*
Y845550D03*
X493499Y865050D03*
Y884050D03*
X485799Y920050D03*
Y901050D03*
X486799Y941050D03*
X493099Y996350D03*
X494099Y1017350D03*
X501499Y1102550D03*
X491999Y1115550D03*
X504399Y1132250D03*
X505399Y1153250D03*
X486499Y1210550D03*
Y1196050D03*
X506599Y1202350D03*
Y1216850D03*
X487099Y1218050D03*
X498299Y1323350D03*
X499199Y1350550D03*
X498899Y1386450D03*
Y1408350D03*
X500899Y1434350D03*
X505899Y1466250D03*
X488299Y1531050D03*
X499699Y1538950D03*
X502199Y1566250D03*
X487099Y1606250D03*
X501399Y1634550D03*
X502899Y1709650D03*
X496999Y1799550D03*
X499999Y1854950D03*
X505799Y1893050D03*
X492999Y1878050D03*
X505799Y1912050D03*
X493499Y1909050D03*
X492999Y1897050D03*
X505799Y1921050D03*
X491999Y1924550D03*
X504799Y1939550D03*
X492499Y1955550D03*
X491999Y1943550D03*
X504799Y1967550D03*
Y1958550D03*
X493799Y1977250D03*
X492500Y1987500D03*
X516499Y6550D03*
X522899Y45350D03*
Y64350D03*
X523899Y85350D03*
X520299Y122450D03*
Y141450D03*
X521299Y162450D03*
X508499Y255050D03*
X525999D03*
X515499Y284050D03*
X516899Y306950D03*
X520499Y353550D03*
X509999Y382550D03*
X518999Y416550D03*
X511299Y449150D03*
X519499Y471550D03*
Y489050D03*
X508699Y498950D03*
X518999Y508550D03*
X514499Y546050D03*
X509999Y640550D03*
Y655050D03*
Y672550D03*
X527499Y747150D03*
X525499Y772450D03*
X511199Y782050D03*
X512899Y823550D03*
X526499Y851150D03*
X512899Y842550D03*
X510899Y868150D03*
X522499Y876050D03*
X521999Y895550D03*
X506899Y919950D03*
Y900950D03*
X521999Y914550D03*
X516499Y957050D03*
X514499Y975550D03*
Y990050D03*
Y1007550D03*
X513999Y1046050D03*
Y1027050D03*
X518999Y1103050D03*
X511999Y1115550D03*
X527499Y1181550D03*
X527999Y1212550D03*
X527499Y1200550D03*
X507199Y1224350D03*
X525999Y1231050D03*
X507199Y1252350D03*
Y1243350D03*
X525999Y1245550D03*
X527499Y1278150D03*
X525999Y1263050D03*
X518499Y1346950D03*
X523499Y1360050D03*
X508599Y1370550D03*
X523499Y1379050D03*
X523999Y1391050D03*
X516999Y1418050D03*
Y1437050D03*
X517499Y1449050D03*
X518899Y1530150D03*
X510100Y1579800D03*
X508199Y1610450D03*
X518499Y1643950D03*
X509199Y1660550D03*
X507399Y1683350D03*
X522300Y1739200D03*
X508200Y1758200D03*
X515499Y1779050D03*
X526499Y1801150D03*
X514199Y1815750D03*
X517499Y1855450D03*
X519399Y1876750D03*
Y1904750D03*
Y1895750D03*
X518399Y1923250D03*
Y1951250D03*
Y1942250D03*
X509299Y1977250D03*
X511999Y1987550D03*
X535999Y6550D03*
X541499Y25050D03*
X541999Y46550D03*
X541499Y63550D03*
X541999Y79050D03*
Y93550D03*
Y108050D03*
Y125550D03*
X541499Y145050D03*
Y164050D03*
X528799Y199950D03*
X542499Y185050D03*
X533499Y217550D03*
X540499Y255050D03*
X536499Y283050D03*
X544799Y293950D03*
X540099Y306550D03*
X548100Y362200D03*
X530999Y381550D03*
X538799Y445050D03*
X539799Y466050D03*
X539299Y485550D03*
X535499Y545050D03*
X538999Y562050D03*
X534499Y640050D03*
Y654550D03*
Y672050D03*
X547999Y728550D03*
Y743050D03*
Y760550D03*
X547499Y780050D03*
X534499Y805950D03*
X547499Y799050D03*
X541399Y854450D03*
Y873450D03*
X539299Y935850D03*
X540299Y956850D03*
X540899Y981450D03*
Y1000450D03*
X541899Y1021450D03*
X534599Y1048550D03*
X535599Y1069550D03*
X538499Y1103050D03*
X548999Y1116050D03*
X529499D03*
X546499Y1180750D03*
Y1195250D03*
X547099Y1202750D03*
Y1230750D03*
Y1221750D03*
X548799Y1252850D03*
Y1267350D03*
X530499Y1297050D03*
X545099Y1355250D03*
X540399Y1382150D03*
X538799Y1409750D03*
X536799Y1436350D03*
X528499Y1460250D03*
X546099Y1467550D03*
X538999Y1528350D03*
X529799Y1555050D03*
X533800Y1575500D03*
X529499Y1616550D03*
X528999Y1604550D03*
X532499Y1635550D03*
X532599Y1655650D03*
X532499Y1669550D03*
Y1688550D03*
X532999Y1700550D03*
X538299Y1721050D03*
X532499Y1763050D03*
X539499Y1788150D03*
X544300Y1784638D03*
X531799Y1818450D03*
X538999Y1855950D03*
X547999Y1892350D03*
X533499Y1884050D03*
X547999Y1911350D03*
X533499Y1912050D03*
Y1903050D03*
X547999Y1920350D03*
X532499Y1930550D03*
X546999Y1938850D03*
X532499Y1949550D03*
X546999Y1966850D03*
Y1957850D03*
X546299Y1977250D03*
X528799Y1976750D03*
X532499Y1958550D03*
X531500Y1987500D03*
X551499Y6550D03*
X568099Y72550D03*
Y91550D03*
X569099Y112550D03*
X562799Y127750D03*
Y146750D03*
X563799Y167750D03*
X565999Y199950D03*
X568499Y217550D03*
X552999D03*
X557999Y322550D03*
Y326550D03*
X558099Y335050D03*
X557933Y331010D03*
X555999Y412550D03*
X556499Y467550D03*
Y485050D03*
X555999Y504550D03*
X558499Y562550D03*
Y616050D03*
X554304Y615840D03*
X554499Y624550D03*
X558699D03*
X554499Y620050D03*
X558709Y620245D03*
X565699Y710650D03*
X549999Y710050D03*
X562999Y898050D03*
X560999Y916550D03*
Y931050D03*
Y948550D03*
X560499Y968050D03*
Y987050D03*
X560999Y999050D03*
X558999Y1017550D03*
Y1032050D03*
X558499Y1069050D03*
X558999Y1049550D03*
X558499Y1088050D03*
X568499Y1101550D03*
X553999Y1103050D03*
X564499Y1116050D03*
X567999Y1187550D03*
Y1215550D03*
Y1206550D03*
X565999Y1234050D03*
Y1248550D03*
X566399Y1273850D03*
X549399Y1274850D03*
X561099Y1301050D03*
X549399Y1293850D03*
Y1302850D03*
X555699Y1322950D03*
X559099Y1343250D03*
X557499Y1424050D03*
Y1443050D03*
Y1452050D03*
X563499Y1486550D03*
Y1492050D03*
Y1497550D03*
Y1503550D03*
X567999Y1549950D03*
X552199Y1576650D03*
X552099Y1601950D03*
X569499Y1610550D03*
X553399Y1624550D03*
X569499Y1619550D03*
X554199Y1651950D03*
X555199Y1674750D03*
X555399Y1689350D03*
X555899Y1706750D03*
X556199Y1727050D03*
X560399Y1792550D03*
X555500Y1802700D03*
X554499Y1855950D03*
X562599Y1893450D03*
Y1874450D03*
Y1902450D03*
X561599Y1920950D03*
Y1948950D03*
Y1939950D03*
X570299Y1976250D03*
X568999Y1987050D03*
X553499D03*
X570999Y6050D03*
X588499Y6550D03*
X587999Y25050D03*
X588499Y46550D03*
X587999Y63550D03*
X588499Y125550D03*
X587999Y145050D03*
Y164050D03*
X588999Y185050D03*
X587999Y217050D03*
X572999Y255050D03*
Y269550D03*
Y287050D03*
X572499Y306550D03*
Y325550D03*
X573499Y346550D03*
X579899Y375750D03*
X577399Y420050D03*
X578399Y441050D03*
X577899Y460550D03*
X576099Y481850D03*
X577099Y502850D03*
X576599Y522350D03*
X579499Y561550D03*
X573499Y658550D03*
Y673050D03*
Y690550D03*
X586299Y711250D03*
X577999Y732050D03*
X575999Y750550D03*
Y765050D03*
Y782550D03*
X575499Y802050D03*
Y821050D03*
X576499Y842050D03*
X578299Y895650D03*
Y914650D03*
X583299Y961450D03*
X570899Y946850D03*
X583299Y980450D03*
X570899Y965850D03*
X571899Y986850D03*
X573499Y1036550D03*
Y1055550D03*
X574499Y1076550D03*
X588499Y1101550D03*
X578999Y1114550D03*
X582699Y1233250D03*
X583299Y1255250D03*
X582699Y1247750D03*
X583299Y1274250D03*
X579299Y1300750D03*
X583299Y1283250D03*
X581999Y1370150D03*
X580999Y1412750D03*
X575699Y1438950D03*
X582999Y1461250D03*
X590599Y1483450D03*
X582299Y1534150D03*
X588099Y1572050D03*
X573400Y1577600D03*
X588000Y1604000D03*
X590799Y1627850D03*
X580799Y1646150D03*
X572999Y1675550D03*
X590599Y1694450D03*
X572999Y1694550D03*
Y1703550D03*
X580299Y1722550D03*
X582599Y1740050D03*
X587499Y1844550D03*
X573999Y1855450D03*
X588899Y1882350D03*
X575999Y1888050D03*
X588899Y1910350D03*
Y1901350D03*
X575999Y1907050D03*
X587899Y1928850D03*
X576499Y1919050D03*
X574999Y1934550D03*
X587899Y1956850D03*
Y1947850D03*
X574999Y1953550D03*
X585799Y1976250D03*
X575499Y1965550D03*
X588499Y1986550D03*
X608499Y6550D03*
X603999Y35350D03*
Y54350D03*
X604999Y75350D03*
X603999Y133750D03*
Y152750D03*
X604999Y173750D03*
X605499Y217550D03*
X599299Y344650D03*
X600299Y365650D03*
X599799Y385150D03*
X607399Y380250D03*
X592999Y407550D03*
Y422050D03*
Y439550D03*
X592499Y459050D03*
Y478050D03*
X593499Y499050D03*
X606499Y584550D03*
X595999Y624050D03*
Y609550D03*
Y641550D03*
X605299Y661750D03*
X609499Y708050D03*
X597999Y690050D03*
X607499Y726550D03*
Y741050D03*
Y758550D03*
X606999Y778050D03*
Y797050D03*
X603499Y904050D03*
X601499Y922550D03*
Y937050D03*
Y954550D03*
X600999Y1002050D03*
X611399Y1026650D03*
X598999Y1020550D03*
X611399Y1045650D03*
X598999Y1035050D03*
X612399Y1066650D03*
X598999Y1052550D03*
X598499Y1072050D03*
X605999Y1102050D03*
X598499Y1091050D03*
X598999Y1114550D03*
X603899Y1157850D03*
X597599Y1196050D03*
X596599Y1215050D03*
X600899Y1238650D03*
X598499Y1280550D03*
Y1261550D03*
X598999Y1292550D03*
X608899Y1305050D03*
X605599Y1326350D03*
X606199Y1338250D03*
X599499Y1351550D03*
X599999Y1382550D03*
X599499Y1370550D03*
X604899Y1407750D03*
X601299Y1447650D03*
X610899Y1496750D03*
X599799Y1544650D03*
X611900Y1577900D03*
X612499Y1615550D03*
X611999Y1603550D03*
X600599Y1645450D03*
X593399Y1668850D03*
X609499Y1675050D03*
Y1692050D03*
X607599Y1716450D03*
X606999Y1745550D03*
X593299Y1760950D03*
X608599Y1810750D03*
X595199Y1820910D03*
X611999Y1855950D03*
X591499D03*
X602799Y1887350D03*
Y1906350D03*
X601799Y1933850D03*
X602799Y1915350D03*
X601799Y1952850D03*
Y1961850D03*
X605299Y1975750D03*
X605999Y1987050D03*
X625999Y7050D03*
X624499Y23050D03*
X624999Y44550D03*
X624499Y61550D03*
X624999Y123550D03*
X624499Y143050D03*
Y162050D03*
X625499Y183050D03*
X623899Y202550D03*
X625499Y217550D03*
X627999Y262550D03*
Y248050D03*
Y280050D03*
X627499Y299550D03*
X628200Y320000D03*
X628499Y339550D03*
X632399Y358750D03*
X614999Y371550D03*
X620999Y411550D03*
X621999Y432550D03*
X621499Y452050D03*
Y466550D03*
Y484050D03*
X613700Y504600D03*
X625999Y585050D03*
X620499Y623550D03*
Y609050D03*
X631999Y639650D03*
X622999Y672050D03*
Y689550D03*
X629099Y714050D03*
X633499Y750150D03*
X621499Y767150D03*
X621999Y835050D03*
X612999Y854550D03*
X629499Y853050D03*
Y868550D03*
X613499Y868050D03*
X616699Y948250D03*
Y967250D03*
X617699Y988250D03*
X631999Y1001550D03*
X629999Y1020050D03*
Y1034550D03*
Y1052050D03*
X629499Y1071550D03*
Y1090550D03*
X616499Y1115050D03*
X627699Y1143550D03*
X628699Y1164550D03*
X626199Y1183450D03*
X630499Y1243950D03*
X617599Y1246250D03*
X618199Y1268250D03*
X617599Y1260750D03*
X618199Y1296250D03*
Y1287250D03*
X631799Y1322650D03*
X617899Y1360850D03*
X632499Y1347950D03*
X625499Y1383450D03*
X627499Y1406050D03*
X626799Y1432350D03*
X625199Y1489150D03*
X617699Y1530350D03*
X623499Y1564050D03*
X633499Y1615450D03*
X628499Y1636650D03*
X627299Y1659550D03*
X625499Y1725050D03*
X619499Y1803150D03*
X627273Y1793905D03*
X626999Y1800050D03*
X632799Y1820450D03*
X627494Y1829068D03*
X627499Y1855950D03*
X630699Y1872750D03*
Y1891750D03*
Y1900750D03*
X616499Y1913050D03*
Y1894050D03*
X629699Y1919250D03*
X616499Y1922050D03*
X629699Y1947250D03*
Y1938250D03*
X615499Y1940550D03*
X622799Y1976250D03*
X615499Y1959550D03*
Y1968550D03*
X626999Y1987050D03*
X645499Y7050D03*
X651799Y40650D03*
Y59650D03*
X652799Y80650D03*
X649899Y138350D03*
Y157350D03*
X650899Y178350D03*
X642999Y218050D03*
X653999Y286550D03*
X635399Y376250D03*
X643599Y395950D03*
X644599Y416950D03*
X644099Y450950D03*
Y436450D03*
X642499Y525750D03*
X643499Y546750D03*
X642999Y566250D03*
X646999Y584550D03*
X640599Y604650D03*
X645099Y639150D03*
X647499Y657050D03*
Y671550D03*
X648999Y702350D03*
X647499Y689050D03*
X651999Y718350D03*
X647399Y742150D03*
X653099Y803350D03*
X645799Y816650D03*
X641599Y843250D03*
Y862250D03*
X642599Y883250D03*
X636999Y914050D03*
X639499Y952150D03*
Y971150D03*
X633999Y1103050D03*
X641799Y1137650D03*
X650299Y1153150D03*
X651299Y1174150D03*
X650599Y1182050D03*
X651599Y1203050D03*
X638999Y1267550D03*
Y1286550D03*
Y1295550D03*
X654499Y1354050D03*
Y1373050D03*
X652999Y1403550D03*
Y1418050D03*
Y1435550D03*
X636799Y1461250D03*
X643099Y1541350D03*
X652399Y1575850D03*
X639200Y1576200D03*
X635500Y1603900D03*
X652499Y1618550D03*
Y1609550D03*
X649399Y1644950D03*
X635099Y1691150D03*
X642499Y1709050D03*
X650399Y1771250D03*
X642400Y1800100D03*
X633837Y1807384D03*
X640999Y1815550D03*
X644049Y1810834D03*
X645099Y1877550D03*
X645399Y1906150D03*
X646799Y1926450D03*
X644999Y1934050D03*
Y1953050D03*
X643799Y1976250D03*
X645499Y1965050D03*
X642499Y1987050D03*
X660999Y7050D03*
X674999Y20550D03*
X675499Y42050D03*
Y74550D03*
X674999Y59050D03*
X675499Y89050D03*
Y103550D03*
Y121050D03*
X674999Y140550D03*
Y159550D03*
X675999Y180550D03*
X662499Y218050D03*
X656499Y307050D03*
Y324550D03*
X655999Y344050D03*
X659899Y363250D03*
X666999Y476550D03*
Y491050D03*
Y508550D03*
X666499Y528050D03*
Y547050D03*
X667499Y568050D03*
X674999Y601550D03*
X665999Y623550D03*
X673999Y645150D03*
X665499Y766550D03*
X664999Y786050D03*
Y805050D03*
X665999Y826050D03*
X663999Y844550D03*
Y876550D03*
Y859050D03*
X663499Y896050D03*
Y915050D03*
X664499Y936050D03*
X658999Y959050D03*
X656999Y977550D03*
Y992050D03*
X673999Y1017550D03*
X656999Y1009550D03*
X673999Y1036550D03*
X656499Y1029050D03*
X674699Y1061450D03*
X656499Y1048050D03*
X674699Y1080450D03*
X669499Y1116550D03*
X674999Y1134950D03*
X667199Y1152850D03*
X668199Y1173850D03*
X670199Y1192750D03*
X671199Y1213750D03*
X668699Y1227650D03*
X657099Y1272850D03*
X657799Y1288450D03*
X672999Y1303450D03*
X656399Y1307050D03*
X671999Y1324950D03*
X665699Y1337250D03*
X654999Y1385050D03*
X659699Y1445950D03*
X665699Y1462250D03*
X656099Y1479550D03*
X672399Y1508750D03*
X673699Y1535350D03*
X662099Y1549650D03*
X670699Y1603150D03*
X671399Y1625350D03*
X657099Y1668850D03*
X674999Y1676550D03*
X656499Y1697050D03*
X675499Y1738050D03*
X665399Y1752350D03*
X675499Y1757050D03*
X675999Y1769050D03*
X659159Y1792278D03*
X659549Y1815384D03*
X667999Y1870950D03*
X669399Y1855350D03*
X674899Y1892350D03*
X661299Y1890050D03*
X674899Y1911350D03*
X661299Y1909050D03*
X674899Y1920350D03*
X661299Y1918050D03*
X673899Y1938850D03*
X660299Y1936550D03*
Y1955550D03*
X673899Y1966850D03*
Y1957850D03*
X660299Y1964550D03*
X659299Y1976250D03*
X661999Y1986550D03*
X680499Y6550D03*
X694999Y62650D03*
Y81650D03*
X695999Y102650D03*
X688999Y196550D03*
X677999Y218050D03*
X683499Y263050D03*
Y248550D03*
X680500Y280700D03*
X682999Y300050D03*
Y319050D03*
X683999Y340050D03*
X694999Y480550D03*
X695999Y501550D03*
X695499Y521050D03*
X691399Y548350D03*
X692399Y569350D03*
X691899Y588850D03*
X690499Y623050D03*
X693999Y648150D03*
X678499Y671050D03*
X679299Y703050D03*
X678499Y688550D03*
X681899Y713650D03*
X696299Y741850D03*
X694599Y763450D03*
X685999Y780050D03*
X687099Y804650D03*
Y823650D03*
X688099Y844650D03*
X687099Y896350D03*
Y915350D03*
X688099Y936350D03*
X678299Y978350D03*
Y997350D03*
X694999Y993050D03*
X692999Y1011550D03*
Y1026050D03*
Y1043550D03*
X692499Y1063050D03*
Y1082050D03*
X689999Y1105550D03*
X695999Y1203050D03*
Y1235050D03*
Y1217550D03*
X684299Y1249550D03*
X695999Y1323350D03*
X677999Y1347550D03*
X694999Y1360050D03*
X680299Y1365850D03*
X694999Y1379050D03*
X681299Y1393150D03*
X692999Y1406550D03*
X694999Y1388050D03*
X678299Y1425050D03*
X692999Y1421050D03*
X686999Y1468850D03*
X685299Y1551950D03*
X681299Y1579150D03*
X693599Y1602450D03*
X686699Y1638650D03*
X691999Y1660550D03*
X693099Y1722350D03*
X690499Y1744950D03*
X694599Y1768450D03*
X693549Y1793134D03*
X686473Y1818375D03*
X686999Y1870250D03*
X690899Y1855850D03*
X696299Y1898850D03*
X676399Y1901150D03*
X695299Y1926450D03*
X685499Y1940050D03*
X696299Y1976250D03*
X678799Y1975750D03*
X685499Y1959050D03*
Y1968050D03*
X679499Y1987050D03*
X697999Y7050D03*
X712499Y6050D03*
X699699Y141750D03*
Y160750D03*
X700699Y181750D03*
X711999Y218050D03*
X711499Y252550D03*
X711999Y307550D03*
Y293050D03*
Y325050D03*
X711499Y344550D03*
X703999Y385550D03*
X712699Y434450D03*
X713699Y455450D03*
X713199Y474950D03*
Y489450D03*
X712599Y521050D03*
X713599Y542050D03*
X713099Y561550D03*
X699999Y610050D03*
X717099Y636050D03*
X702999Y656050D03*
Y688050D03*
Y670550D03*
X710899Y751150D03*
X716599Y736850D03*
X706999Y792550D03*
X707499Y773050D03*
X706999Y811550D03*
X707999Y832550D03*
X705999Y851050D03*
Y865550D03*
X707399Y899550D03*
Y918550D03*
X706499Y942550D03*
X713999Y1017050D03*
Y1031550D03*
X713499Y1068550D03*
X713999Y1049050D03*
X709999Y1105550D03*
X700499Y1118550D03*
X704299Y1132650D03*
X716999Y1148150D03*
X697499Y1153550D03*
X717999Y1169150D03*
X697499Y1172550D03*
X713399Y1178750D03*
X697999Y1184550D03*
X713599Y1214650D03*
X714399Y1199750D03*
X708699Y1243550D03*
X709699Y1264550D03*
X707899Y1346250D03*
X702299Y1404450D03*
X713899Y1386450D03*
X716899Y1459850D03*
X700899Y1450250D03*
X716199Y1503050D03*
X714599Y1533950D03*
X708899Y1549250D03*
X698599Y1568550D03*
X706700Y1579900D03*
X717099Y1702450D03*
X702599Y1730550D03*
X715999Y1744050D03*
X709099Y1751850D03*
X715999Y1763050D03*
Y1772050D03*
X706549Y1793634D03*
X717000Y1812384D03*
X705000Y1811900D03*
X711500Y1817700D03*
X704300Y1828400D03*
X697999Y1844550D03*
X706399Y1855850D03*
X705599Y1891850D03*
X716599Y1918450D03*
X698299Y1948050D03*
X711899Y1944050D03*
X709199Y1962950D03*
X717999Y1987550D03*
X702499D03*
X729999Y6550D03*
X725499Y23550D03*
X725999Y45050D03*
X725499Y62050D03*
X725999Y77550D03*
Y92050D03*
Y106550D03*
X738199Y137450D03*
X725999Y124050D03*
X725499Y143550D03*
Y162550D03*
X726499Y183550D03*
X728899Y204550D03*
X729499Y218550D03*
X723200Y275500D03*
X737999Y467050D03*
X738999Y488050D03*
X738499Y507550D03*
Y539550D03*
Y522050D03*
X737999Y559050D03*
X731499Y572050D03*
Y586550D03*
Y604050D03*
X721499Y617550D03*
X729699Y640350D03*
X723499Y654850D03*
X739399Y688150D03*
X720899Y712250D03*
X732499Y729250D03*
X727099Y715050D03*
X733799Y761450D03*
X723999Y783350D03*
Y802350D03*
X724999Y823350D03*
X728499Y841850D03*
X729999Y862850D03*
Y881850D03*
X730999Y902850D03*
X723699Y936250D03*
Y955250D03*
X724699Y976250D03*
X734999Y1030550D03*
Y1045050D03*
Y1062550D03*
X727499Y1106050D03*
X737999Y1119050D03*
X720499Y1118550D03*
X727499Y1132650D03*
X737999Y1159550D03*
Y1187550D03*
Y1178550D03*
X735999Y1206050D03*
X725499Y1231650D03*
X735999Y1220550D03*
X725499Y1250650D03*
X723499Y1278150D03*
X725499Y1259650D03*
X723499Y1292650D03*
X719199Y1322350D03*
X739199Y1348950D03*
X734199Y1373850D03*
X736199Y1399050D03*
X737799Y1428350D03*
X721899Y1419050D03*
X719499Y1446650D03*
X729199Y1492750D03*
X735799Y1533650D03*
X734499Y1563550D03*
X722199Y1564250D03*
X719999Y1605050D03*
X732999Y1620050D03*
X738799Y1677250D03*
X727399Y1694350D03*
X739199Y1716750D03*
X721199Y1723750D03*
X729999Y1756450D03*
X729499Y1778750D03*
X728099Y1844750D03*
X723199Y1867950D03*
X725899Y1855350D03*
X732999Y1868550D03*
X728299Y1888850D03*
X732199Y1878750D03*
X728799Y1908150D03*
Y1933050D03*
X736799Y1919450D03*
X730499Y1954650D03*
X721499Y1974550D03*
X737499Y1987050D03*
X749499Y6550D03*
X759999Y39550D03*
X751499Y48350D03*
X757499Y44050D03*
Y63050D03*
X758499Y84050D03*
X752099Y112150D03*
X757999Y154550D03*
Y159050D03*
X753999Y154550D03*
Y159050D03*
X749499Y218550D03*
X755499Y314550D03*
X755346Y319149D03*
X751539Y313984D03*
X751499Y318050D03*
X749899Y398550D03*
X750899Y419550D03*
X750399Y453550D03*
Y439050D03*
X755199Y488150D03*
X756199Y509150D03*
X755699Y528650D03*
X754499Y564650D03*
X755499Y585650D03*
X754999Y605150D03*
X744999Y626550D03*
X751499Y679148D03*
X757400Y686300D03*
X747999Y670750D03*
X754999Y694050D03*
X749999Y700050D03*
X749499Y716050D03*
X744999Y715550D03*
X749999Y720050D03*
X745499D03*
X749799Y767450D03*
X743099Y785350D03*
X751999Y817050D03*
X751499Y855550D03*
Y836550D03*
X751599Y887350D03*
Y906350D03*
X752599Y927350D03*
X749999Y946550D03*
Y965550D03*
X751399Y1004550D03*
X750999Y986550D03*
X751399Y1023550D03*
X752399Y1052550D03*
X753999Y1100050D03*
X755499Y1119050D03*
X749999Y1119550D03*
X748999Y1115550D03*
X748499Y1111550D03*
X758799Y1171150D03*
Y1190150D03*
Y1199150D03*
X756799Y1232150D03*
Y1217650D03*
X757399Y1258650D03*
Y1239650D03*
X740499Y1252550D03*
X757399Y1267650D03*
X740499Y1270050D03*
X740799Y1298750D03*
X755399Y1300650D03*
Y1286150D03*
X742099Y1320650D03*
X754999Y1420050D03*
Y1437550D03*
X741099Y1450250D03*
Y1498150D03*
X747199Y1509150D03*
X755499Y1507550D03*
X751000Y1517000D03*
X757500Y1522500D03*
X751000Y1521000D03*
Y1525000D03*
X755499Y1568550D03*
X743400Y1578700D03*
X751300Y1604900D03*
X756299Y1679050D03*
X750099Y1694950D03*
X756499Y1712150D03*
X747499Y1734350D03*
X756900Y1766000D03*
X752900D03*
X751899Y1752150D03*
X747799Y1766750D03*
X751999Y1775550D03*
X756617Y1780067D03*
X752657Y1779496D03*
X755999Y1775550D03*
X753558Y1769946D03*
X757518Y1770517D03*
X744049Y1791634D03*
X740549Y1802634D03*
X753949Y1798194D03*
X740549Y1810384D03*
X747599Y1844250D03*
X744699Y1868450D03*
X758399Y1868350D03*
X743399Y1855850D03*
X743799Y1888850D03*
X753699Y1879250D03*
X755299Y1902150D03*
X739799D03*
X755500Y1914500D03*
X755999Y1935050D03*
X756499Y1942550D03*
X746499Y1974250D03*
X754999Y1987550D03*
X764999Y6550D03*
X763399Y24150D03*
X774399Y54050D03*
X775399Y80250D03*
X778399Y105250D03*
X767399Y140150D03*
X760799Y181950D03*
X779399Y200550D03*
X766999Y219050D03*
X776199Y323050D03*
X772873Y330624D03*
X781478Y363924D03*
X776978D03*
X772478Y359924D03*
Y363924D03*
X774999Y476550D03*
Y462050D03*
Y494050D03*
X774499Y513550D03*
Y532550D03*
X775499Y553550D03*
X777499Y638050D03*
X764599Y655750D03*
X777499Y664550D03*
X771800Y686600D03*
X766499Y699050D03*
Y705550D03*
X770999Y726750D03*
X774199Y733050D03*
X771196Y764382D03*
Y760382D03*
X775696Y764382D03*
X780196D03*
X778999Y806950D03*
X763099Y796350D03*
X775199Y839250D03*
Y858250D03*
X776199Y879250D03*
X772199Y920650D03*
Y939650D03*
X773199Y960650D03*
X776899Y988050D03*
Y1007050D03*
X777899Y1028050D03*
X760999Y1095550D03*
X773499Y1101050D03*
X769499D03*
X773499Y1105050D03*
X769499D03*
X768306Y1124321D03*
X774383Y1133235D03*
X780333Y1165892D03*
X775833D03*
X771333Y1161892D03*
Y1165892D03*
X762499Y1335550D03*
X779399Y1361850D03*
X762499Y1353050D03*
X773999Y1393450D03*
X763399Y1401450D03*
X769300Y1488100D03*
X779000Y1488400D03*
X771399Y1474550D03*
X770999Y1500050D03*
X780499D03*
X773499Y1509050D03*
X769499D03*
X774542Y1526350D03*
X774488Y1537495D03*
X778327Y1569796D03*
X773327Y1565796D03*
X773827Y1569796D03*
X768500Y1577500D03*
X776999Y1647650D03*
X765099Y1664950D03*
X770399Y1699650D03*
X779999Y1717050D03*
X770099Y1730350D03*
X779899Y1748150D03*
X765600Y1756800D03*
X767159Y1792364D03*
X765099Y1844750D03*
X779699Y1867950D03*
X779399Y1855850D03*
X763899D03*
X780799Y1888850D03*
X763299Y1888350D03*
X769199Y1879250D03*
X774499Y1908050D03*
X765999D03*
X773999Y1923550D03*
X767999Y1923050D03*
X774499Y1930050D03*
X768999D03*
X775999Y1916050D03*
X768499Y1917550D03*
X775199Y1940050D03*
X766400Y1971600D03*
X775814Y1975699D03*
X770814Y1971713D03*
X771814Y1975713D03*
X777499Y1987550D03*
X784499Y6050D03*
X801999Y6550D03*
X796999Y27050D03*
X797499Y48550D03*
X796999Y65550D03*
X797499Y81050D03*
Y95550D03*
Y110050D03*
X796599Y123450D03*
X797499Y127550D03*
X796999Y147050D03*
Y166050D03*
X797999Y187050D03*
X786499Y219050D03*
X800999Y216550D03*
X796873Y307571D03*
Y303071D03*
Y298571D03*
Y294071D03*
X795199Y333050D03*
X789999Y340250D03*
X784478Y355424D03*
Y359924D03*
X789999Y570050D03*
Y602050D03*
Y584550D03*
X785499Y641050D03*
X794999Y664550D03*
X786500Y686100D03*
X798000Y686400D03*
X782999Y699550D03*
X794331Y698353D03*
Y702853D03*
Y707353D03*
X791999Y729350D03*
X794331Y711853D03*
X785826Y737954D03*
X799385Y757436D03*
Y761436D03*
X783196Y760382D03*
Y755882D03*
X802499Y814550D03*
X801999Y834050D03*
Y853050D03*
X800999Y892550D03*
Y907050D03*
Y924550D03*
X800499Y944050D03*
Y963050D03*
X801499Y984050D03*
X800999Y1005550D03*
Y1020050D03*
Y1037550D03*
X783999Y1096550D03*
X789499Y1099550D03*
X802499Y1097566D03*
X798499D03*
X782672Y1129146D03*
X795854Y1135926D03*
X788854Y1142626D03*
X783333Y1157392D03*
Y1161892D03*
X790999Y1194550D03*
Y1175550D03*
X791499Y1206550D03*
X789499Y1225050D03*
Y1257050D03*
Y1239550D03*
X788999Y1278150D03*
X791999Y1294450D03*
X795299Y1326650D03*
X799999Y1340550D03*
X798299Y1344250D03*
X799999Y1358050D03*
X781999Y1434650D03*
X786500Y1488600D03*
X801300Y1489000D03*
X786999Y1506550D03*
X795999Y1509550D03*
Y1504550D03*
Y1518550D03*
Y1514050D03*
X787799Y1543550D03*
X797699Y1541050D03*
X785827Y1561296D03*
Y1565796D03*
X782827Y1569796D03*
X797299Y1646650D03*
X802899Y1670550D03*
X782999Y1668050D03*
Y1687050D03*
X783499Y1699050D03*
X794499Y1734550D03*
X787900Y1758800D03*
X801099Y1844750D03*
X785599D03*
X791799Y1855850D03*
X797199Y1868450D03*
X788699Y1878750D03*
X783499Y1907050D03*
X790499Y1913050D03*
X795526Y1909696D03*
X795493Y1913696D03*
X795501Y1917696D03*
X795499Y1922050D03*
X790844Y1952360D03*
X799297Y1959333D03*
X783814Y1967213D03*
Y1971713D03*
X784016Y1975708D03*
X789299Y1983850D03*
X792999Y1987550D03*
X818999Y6050D03*
X817599Y43750D03*
X813299Y49350D03*
Y68350D03*
X814299Y89350D03*
X813299Y110850D03*
X821199Y137450D03*
X805899Y126150D03*
X822200Y258000D03*
X816500Y270600D03*
X809373Y307571D03*
Y297571D03*
Y292571D03*
X808999Y303050D03*
X821499Y314050D03*
X819299Y413250D03*
Y394250D03*
X820299Y434250D03*
X802999Y466050D03*
X803999Y487050D03*
X803499Y506550D03*
Y538550D03*
Y521050D03*
X802999Y558050D03*
X814499Y569550D03*
Y601550D03*
Y584050D03*
X809700Y686300D03*
X806300Y670600D03*
X820900Y668000D03*
X812800Y679900D03*
X806831Y701853D03*
Y706853D03*
X806999Y697050D03*
X806831Y711853D03*
X811499Y767550D03*
Y782050D03*
Y799550D03*
X802999Y874050D03*
X815400Y1082500D03*
X811499Y1097050D03*
X807499D03*
X807341Y1111216D03*
Y1101216D03*
X806999Y1106050D03*
X807341Y1116216D03*
X806899Y1151850D03*
X808299Y1175850D03*
X806599Y1189750D03*
X803599Y1211050D03*
X810199Y1229350D03*
Y1248350D03*
Y1257350D03*
X808199Y1275850D03*
X811999Y1293550D03*
X808199Y1290350D03*
X822199Y1335250D03*
X819199Y1353550D03*
X806499Y1390550D03*
X803299Y1426650D03*
X806499Y1408050D03*
X805899Y1464250D03*
X809245Y1508722D03*
Y1503722D03*
Y1518722D03*
X808999Y1513550D03*
X804899Y1553250D03*
X813300Y1604100D03*
X803599Y1618350D03*
X814599Y1642650D03*
X823499Y1674050D03*
X808899Y1698450D03*
X823499Y1693050D03*
Y1702050D03*
X824100Y1719900D03*
X819400Y1721900D03*
X819200Y1727100D03*
X808299Y1755250D03*
X809299Y1856350D03*
X818900Y1870800D03*
X806199Y1879250D03*
X807936Y1914865D03*
Y1910365D03*
X807997Y1922865D03*
X808005Y1918865D03*
X813599Y1979950D03*
X812499Y1987050D03*
X836499Y6550D03*
X824899Y25150D03*
X844799Y19850D03*
X839999Y46050D03*
X840499Y55050D03*
X840999Y62550D03*
X841499Y71550D03*
X843499Y82550D03*
X838999Y85050D03*
X837999Y91050D03*
X838499Y107050D03*
Y99550D03*
X839499Y119050D03*
X837499Y138550D03*
X838499Y145050D03*
X838999Y313550D03*
X838499Y352050D03*
X839299Y390950D03*
Y409950D03*
X840299Y430950D03*
X824899Y500450D03*
X825899Y521450D03*
X825399Y540950D03*
X834599Y543050D03*
X835599Y564050D03*
X835099Y583550D03*
X841000Y671100D03*
X836149Y714050D03*
X835999Y767050D03*
X837799Y754150D03*
X835999Y781550D03*
Y799050D03*
X825199Y850850D03*
X827699Y873450D03*
Y892450D03*
X828699Y913450D03*
X826999Y963150D03*
Y982150D03*
X827999Y1003150D03*
X825500Y1076300D03*
X841999Y1118550D03*
X836149D03*
X839999Y1157550D03*
X831499Y1181550D03*
Y1209550D03*
Y1200550D03*
X829499Y1228050D03*
Y1242550D03*
X828199Y1267850D03*
X826199Y1294450D03*
X831499Y1324950D03*
X841999Y1341050D03*
Y1358550D03*
X825500Y1379000D03*
X834499Y1397550D03*
X836600Y1416500D03*
X843999Y1523550D03*
X839499D03*
X839899Y1562050D03*
X825999Y1578050D03*
X826499Y1609050D03*
X827199Y1622750D03*
X841499Y1638950D03*
X837199Y1660550D03*
X839199Y1683550D03*
X842799Y1701150D03*
X829200Y1719800D03*
X844499Y1788050D03*
X842500Y1799000D03*
X827999Y1791550D03*
X829799Y1856350D03*
X833199Y1868450D03*
X842199Y1879250D03*
X833100Y1878500D03*
X833999Y1883050D03*
X843999Y1928550D03*
X838999D03*
X835114Y1951150D03*
X840999Y1970550D03*
X829499Y1980250D03*
X829999Y1987550D03*
X855999Y6550D03*
X860799Y24150D03*
X849999Y44550D03*
X865499Y39550D03*
X854499D03*
X848499Y67550D03*
X856499Y71050D03*
X849499Y91050D03*
X855499Y82050D03*
X845999Y111050D03*
X853999Y132550D03*
X847999Y119550D03*
X865499Y125550D03*
X849999Y145550D03*
X864199Y321524D03*
X863999Y313550D03*
X858400Y352300D03*
X847999Y352550D03*
X854499Y387550D03*
Y373050D03*
Y405050D03*
X853999Y424550D03*
Y443550D03*
X854999Y464550D03*
X860199Y525050D03*
X861199Y546050D03*
X860699Y565550D03*
X861800Y591200D03*
X860499Y607550D03*
X860796Y678632D03*
X859999Y713050D03*
Y767550D03*
X856299Y753150D03*
X846799Y754150D03*
X865000Y752100D03*
X859999Y782050D03*
Y799550D03*
X847799Y828250D03*
X857099Y873450D03*
X866199Y920350D03*
Y901350D03*
X850999Y962550D03*
Y943550D03*
X851999Y983550D03*
X859999Y1118550D03*
X846499Y1170450D03*
X856400Y1157700D03*
X848999Y1158050D03*
X863300Y1153800D03*
X860499Y1192550D03*
X845799Y1190450D03*
X849799Y1199750D03*
X851999Y1237550D03*
Y1218550D03*
X852499Y1249550D03*
X850499Y1268050D03*
X860099Y1295450D03*
X850499Y1300050D03*
Y1282550D03*
X861849Y1383500D03*
X864799Y1532050D03*
X861999Y1522550D03*
X863838Y1542478D03*
X850099Y1572250D03*
X858400Y1561900D03*
X850499Y1562050D03*
X865300Y1557700D03*
X864000Y1578200D03*
X849900Y1605100D03*
X852499Y1621350D03*
X855799Y1658250D03*
X855350Y1703201D03*
X864099Y1683550D03*
X860085Y1715214D03*
X853799Y1790850D03*
X863099Y1813150D03*
X862499Y1823550D03*
X854977Y1818994D03*
X863699Y1902750D03*
X861414Y1928550D03*
X860799Y1917250D03*
X864414Y1944050D03*
Y1940050D03*
X850499Y1977950D03*
X856999Y1970050D03*
X849999Y1970550D03*
X865200Y1968000D03*
X864999Y1987050D03*
X849499D03*
X871499Y6550D03*
X885999Y21150D03*
X883999Y39050D03*
X881499Y70550D03*
X866999D03*
X878499Y91550D03*
X876999Y82050D03*
X867499D03*
X886499Y99550D03*
Y104550D03*
X872499Y133050D03*
X881999Y119550D03*
X875499Y125550D03*
X871499Y146050D03*
X871786Y218924D03*
Y203924D03*
X887400Y233555D03*
X871786Y233924D03*
X887400Y259700D03*
X879878Y247724D03*
X872999Y294624D03*
X869399Y288124D03*
X870600Y346700D03*
X872599Y336224D03*
X875799Y386250D03*
Y405250D03*
X876799Y426250D03*
X884399Y443450D03*
Y462450D03*
X885399Y483450D03*
X870719Y609705D03*
X870773Y624705D03*
X870719Y639705D03*
X887401Y665000D03*
X881125Y652050D03*
X871786Y679436D03*
Y709482D03*
X871499Y689436D03*
X870499Y724550D03*
X866499D03*
X871385Y719436D03*
X884499Y767050D03*
Y781550D03*
Y799050D03*
X873999Y830550D03*
Y845050D03*
Y862550D03*
X886999Y907350D03*
X867199Y941350D03*
X886999Y947250D03*
X870777Y1014948D03*
X870468Y1030227D03*
X886919Y1044478D03*
X870298Y1045227D03*
X880033Y1058592D03*
X887400Y1070600D03*
X868399Y1128950D03*
X871399Y1182850D03*
Y1201850D03*
Y1210850D03*
X869399Y1229350D03*
Y1243850D03*
X872099Y1268150D03*
X871399Y1291450D03*
X875399Y1322650D03*
X873499Y1356050D03*
X870294Y1375659D03*
X868499Y1392550D03*
Y1410050D03*
X871836Y1420460D03*
X886913Y1449010D03*
X871836Y1435460D03*
X879727Y1463696D03*
X871836Y1450460D03*
X887499Y1476050D03*
X866516Y1498533D03*
X873099Y1572550D03*
X886900Y1604100D03*
X866499Y1603050D03*
Y1612050D03*
X868099Y1635650D03*
X887299Y1620050D03*
X877699Y1646650D03*
X882999Y1678250D03*
X879200Y1698700D03*
X879900Y1709300D03*
X883900Y1709500D03*
X875900D03*
X887000Y1721400D03*
X882700Y1738300D03*
X886900Y1737900D03*
X872950Y1744401D03*
X871283Y1736317D03*
X866699Y1770950D03*
X879399Y1798150D03*
X869634Y1826876D03*
X871836Y1840972D03*
X887499Y1855550D03*
X869999Y1855972D03*
X887401Y1881500D03*
X879399Y1974550D03*
X873399Y1963650D03*
X868699Y1983250D03*
X884499Y1986550D03*
X890999Y6050D03*
X908499Y6550D03*
X902999Y22050D03*
X902499Y35050D03*
X893999Y46550D03*
X890999Y73050D03*
X905499Y56550D03*
X904999Y61550D03*
X904499Y74050D03*
X904999Y67550D03*
X890459Y100116D03*
X890499Y104550D03*
X898999D03*
X889999Y132550D03*
X904499Y121550D03*
X891999Y146050D03*
X906999Y243150D03*
Y224150D03*
X907999Y264150D03*
X906399Y295250D03*
Y314250D03*
X907399Y335250D03*
X904999Y370550D03*
Y385050D03*
Y402550D03*
X904499Y422050D03*
Y441050D03*
X905499Y462050D03*
X903999Y574378D03*
X898999Y622050D03*
Y604550D03*
X894000Y642400D03*
X900999Y652550D03*
Y670050D03*
X895999Y702550D03*
Y720050D03*
X898499Y830050D03*
Y844550D03*
X889699Y876050D03*
X898499Y862050D03*
X897299Y1182450D03*
X887999Y1209350D03*
X892499Y1224550D03*
Y1252550D03*
Y1243550D03*
X890499Y1271050D03*
Y1285550D03*
X890999Y1336550D03*
Y1354050D03*
X894499Y1423550D03*
Y1441050D03*
X895499Y1488050D03*
X902759Y1509585D03*
X894499Y1522050D03*
Y1539550D03*
X907500Y1604000D03*
X895999Y1661250D03*
X903599Y1686850D03*
X893200Y1721300D03*
X902900Y1709800D03*
X892517Y1714217D03*
X893200Y1730000D03*
X904814Y1789113D03*
X903299Y1814750D03*
X894999Y1829050D03*
X905299Y1852650D03*
X894000Y1868452D03*
X900299Y1876950D03*
X897299Y1904150D03*
X907599Y1930050D03*
X897599Y1938750D03*
X904299Y1954950D03*
X901999Y1987050D03*
X923999Y6050D03*
X917499Y21550D03*
X909499D03*
X909999Y35550D03*
X916499Y36050D03*
X927999Y38050D03*
X928499Y51550D03*
X920900Y54700D03*
X928999Y56050D03*
X928499Y60550D03*
X928999Y65550D03*
X918499Y107050D03*
X919542Y124007D03*
X913699Y484650D03*
Y503650D03*
X914699Y524650D03*
X918999Y641550D03*
Y656050D03*
Y673550D03*
X918499Y693050D03*
Y712050D03*
X921899Y744850D03*
X919499Y733050D03*
X921899Y759350D03*
Y776850D03*
X921399Y796350D03*
X922399Y836350D03*
X921399Y815350D03*
X920399Y854850D03*
Y869350D03*
Y886850D03*
X919899Y906350D03*
Y925350D03*
X920899Y946350D03*
X921499Y999050D03*
Y1013550D03*
Y1031050D03*
X920999Y1050550D03*
Y1069550D03*
X925499Y1103550D03*
X921999Y1090550D03*
X925499Y1118050D03*
Y1135550D03*
X924999Y1174050D03*
Y1155050D03*
X925999Y1195050D03*
Y1207050D03*
Y1221550D03*
Y1239050D03*
X925499Y1258550D03*
Y1277550D03*
X926499Y1298550D03*
X928499Y1325350D03*
X925999Y1365050D03*
Y1379550D03*
Y1397050D03*
X925499Y1416550D03*
Y1435550D03*
X926499Y1456550D03*
X924999Y1485550D03*
Y1471050D03*
Y1503050D03*
X914599Y1521650D03*
X924499Y1522550D03*
X910899Y1549250D03*
X924499Y1541550D03*
X909700Y1576400D03*
X925499Y1562550D03*
X925599Y1612050D03*
X923599Y1634350D03*
X908899Y1630050D03*
X914899Y1657550D03*
X922599Y1682150D03*
X911299Y1800850D03*
X928000Y1818500D03*
X922899Y1853650D03*
X914999Y1868050D03*
Y1887050D03*
X914899Y1912450D03*
X915499Y1899050D03*
X916599Y1942650D03*
X914899Y1972250D03*
X921499Y1986550D03*
X941499Y6550D03*
X929999Y32550D03*
X940499Y33050D03*
X945499Y33550D03*
X943499Y48050D03*
X934999Y67050D03*
X943499Y55050D03*
Y72550D03*
X942999Y61550D03*
Y66550D03*
X943499Y78050D03*
X945499Y116550D03*
X939199Y142050D03*
X932499Y191550D03*
Y206050D03*
Y223550D03*
X931999Y243050D03*
Y262050D03*
X932999Y283050D03*
X933499Y304050D03*
Y318550D03*
Y336050D03*
X932999Y355550D03*
Y374550D03*
X933999Y395550D03*
X933499Y429550D03*
Y415050D03*
Y447050D03*
X932999Y466550D03*
Y485550D03*
X933999Y506550D03*
X935499Y539050D03*
Y524550D03*
Y556550D03*
X934999Y576050D03*
X950299Y599650D03*
X934999Y595050D03*
X950299Y614150D03*
X935999Y616050D03*
X950299Y631650D03*
X949799Y651150D03*
Y670150D03*
X950799Y691150D03*
X944499Y750050D03*
Y735550D03*
Y767550D03*
X943999Y787050D03*
Y806050D03*
X944999Y827050D03*
X942999Y845550D03*
Y877550D03*
Y860050D03*
X942499Y897050D03*
Y916050D03*
X943499Y937050D03*
X949299Y977450D03*
Y991950D03*
Y1009450D03*
X948799Y1047950D03*
Y1028950D03*
X949799Y1068950D03*
Y1080950D03*
X950699Y1107750D03*
Y1122250D03*
Y1139750D03*
X950199Y1159250D03*
Y1178250D03*
X950699Y1262750D03*
Y1281750D03*
X943799Y1342950D03*
Y1380850D03*
X944000Y1391900D03*
X946700Y1426500D03*
X944000Y1511300D03*
X943199Y1531650D03*
X933199Y1577550D03*
X944499Y1632650D03*
X950100Y1626100D03*
X940499Y1656950D03*
X941499Y1679550D03*
X931499Y1702050D03*
X949799Y1756250D03*
X941800Y1787700D03*
X941499Y1776250D03*
X934200Y1793500D03*
X932199Y1801850D03*
X937199Y1869950D03*
X937499Y1893850D03*
X938199Y1917150D03*
X947499Y1936050D03*
X930999Y1931050D03*
X945199Y1946350D03*
X930999Y1950050D03*
X946199Y1966650D03*
X931499Y1962050D03*
X930199Y1979550D03*
X936999Y1986550D03*
X960999Y6550D03*
X954799Y17850D03*
X965999Y47050D03*
X951899Y45550D03*
X965999Y56050D03*
Y64050D03*
X966499Y73050D03*
Y82050D03*
X951499Y81050D03*
X961568Y113567D03*
X968399Y137150D03*
X967399Y180350D03*
X958799Y167350D03*
X956099Y181350D03*
X952799Y199150D03*
Y213650D03*
Y231150D03*
X952299Y250650D03*
Y269650D03*
X953299Y290650D03*
X952799Y324650D03*
Y310150D03*
Y342150D03*
X952299Y361650D03*
Y380650D03*
X953299Y401650D03*
X954799Y434150D03*
Y419650D03*
Y451650D03*
X966199Y473350D03*
Y492350D03*
X951799Y489650D03*
X967199Y513350D03*
X951799Y504150D03*
Y521650D03*
X951299Y560150D03*
Y541150D03*
X966799Y566350D03*
X952299Y581150D03*
X966799Y585350D03*
X967799Y606350D03*
X969499Y639050D03*
Y653550D03*
Y671050D03*
X968999Y709550D03*
Y690550D03*
X969999Y730550D03*
Y744250D03*
Y758750D03*
Y776250D03*
X969499Y795750D03*
Y814750D03*
X970499Y835750D03*
Y847750D03*
Y862250D03*
X969999Y899250D03*
X970499Y879750D03*
X969999Y918250D03*
X970999Y939250D03*
X971999Y996550D03*
Y1011050D03*
Y1028550D03*
X971499Y1067050D03*
Y1048050D03*
X951199Y1211250D03*
Y1199250D03*
Y1225750D03*
Y1243250D03*
X951699Y1302750D03*
X965099Y1324350D03*
X952499Y1361850D03*
X964400Y1409700D03*
X972000Y1442000D03*
Y1437500D03*
X971700Y1448300D03*
X962500Y1436500D03*
Y1441000D03*
X952800Y1437500D03*
Y1442000D03*
X962200Y1447300D03*
X952500Y1448300D03*
X971500Y1467500D03*
X971700Y1457800D03*
Y1462300D03*
Y1452800D03*
X962000Y1466500D03*
X952300Y1467500D03*
X962200Y1451800D03*
X952500Y1452800D03*
X962200Y1456800D03*
Y1461300D03*
X952500Y1457800D03*
Y1462300D03*
X966000Y1475000D03*
X958800Y1472500D03*
X966000Y1479500D03*
Y1484000D03*
X958800Y1477000D03*
Y1481500D03*
X965700Y1489300D03*
X958500Y1486800D03*
X960200Y1495300D03*
X951500D03*
X960049Y1500300D03*
X951349D03*
X960049Y1504800D03*
X951349D03*
X966600Y1529100D03*
X961400Y1528700D03*
X961900Y1522400D03*
X967100Y1522800D03*
X962100Y1516000D03*
X967300Y1516400D03*
X961600Y1534400D03*
X972000Y1547500D03*
X966100D03*
X960900Y1547100D03*
X961400Y1540800D03*
X966600Y1541200D03*
X966800Y1534800D03*
X961600Y1552900D03*
X966800Y1553300D03*
X972000Y1566000D03*
X966100D03*
X960900Y1565600D03*
X961400Y1559300D03*
X966600Y1559700D03*
X961900Y1572400D03*
X967100Y1572800D03*
X966400Y1585500D03*
X961200Y1585100D03*
X961700Y1578800D03*
X966900Y1579200D03*
X966500Y1592000D03*
X961300Y1591600D03*
X966300Y1598400D03*
X961100Y1598000D03*
X960600Y1604300D03*
X971700Y1604700D03*
X965800D03*
X957799Y1646950D03*
X955499Y1690850D03*
X958799Y1715750D03*
X965349Y1742000D03*
X954499Y1783550D03*
X971000Y1803000D03*
X971500Y1871500D03*
X966799Y1892150D03*
X955499Y1893050D03*
Y1902050D03*
X954099Y1915450D03*
X955799Y1951950D03*
X971499Y1956050D03*
Y1937050D03*
X953799Y1977950D03*
X971499Y1965050D03*
X956499Y1986050D03*
X976499Y6550D03*
X974699Y21450D03*
X991399Y22450D03*
X977399Y44050D03*
X974699Y64650D03*
X991999Y56050D03*
X983099Y83650D03*
X977699Y109150D03*
X981099Y123450D03*
X988699Y174350D03*
X982999Y189050D03*
Y203550D03*
Y221050D03*
X982499Y240550D03*
Y259550D03*
X983499Y280550D03*
X983999Y301550D03*
Y316050D03*
Y333550D03*
X983499Y353050D03*
Y372050D03*
X983999Y412550D03*
X984499Y393050D03*
X983999Y427050D03*
Y444550D03*
X983499Y464050D03*
Y483050D03*
X984499Y504050D03*
X985999Y536550D03*
Y522050D03*
Y554050D03*
X985499Y573550D03*
Y592550D03*
X986499Y613550D03*
X992999Y894550D03*
Y913550D03*
X972499Y1088050D03*
X975999Y1101050D03*
Y1115550D03*
X975499Y1152550D03*
X975999Y1133050D03*
X975499Y1171550D03*
X976499Y1192550D03*
Y1204550D03*
Y1219050D03*
Y1236550D03*
X975999Y1256050D03*
Y1275050D03*
X976999Y1296050D03*
X975100Y1342600D03*
X976499Y1362550D03*
Y1377050D03*
X992500Y1397300D03*
X973500Y1483000D03*
Y1478500D03*
X973200Y1488300D03*
X973500Y1474000D03*
X972549Y1502300D03*
Y1506800D03*
X972700Y1497300D03*
X973200Y1516400D03*
X972500Y1529100D03*
X973000Y1522800D03*
X972700Y1534800D03*
X972500Y1541200D03*
X972700Y1553300D03*
X972500Y1559700D03*
X973000Y1572800D03*
X972300Y1585500D03*
X972800Y1579200D03*
X972400Y1592000D03*
X972200Y1598400D03*
X989999Y1718050D03*
X993299Y1734350D03*
X976600Y1757100D03*
X976399Y1772250D03*
Y1791150D03*
X974699Y1914450D03*
X991999Y1915750D03*
X992299Y1929050D03*
X980999Y1933350D03*
X987999Y1949050D03*
Y1971950D03*
X989999Y1962650D03*
X973999Y1986550D03*
X995999Y6050D03*
X1013499Y6550D03*
X1002699Y40050D03*
X1005299Y71350D03*
X994399Y101250D03*
X1010599Y115550D03*
X1005299Y179950D03*
Y194450D03*
Y211950D03*
X1004799Y231450D03*
Y250450D03*
X1005799Y271450D03*
X1005299Y305450D03*
Y290950D03*
Y322950D03*
X1004799Y342450D03*
Y361450D03*
X1005799Y382450D03*
X1007299Y400450D03*
Y432450D03*
Y414950D03*
X1000699Y463350D03*
Y482350D03*
X1001699Y503350D03*
X1003999Y526850D03*
X1003499Y546350D03*
Y565350D03*
X1004499Y586350D03*
X1005999Y618850D03*
Y604350D03*
Y636350D03*
X994999Y747550D03*
Y733050D03*
Y765050D03*
X994499Y784550D03*
Y803550D03*
X995499Y824550D03*
X993499Y857550D03*
Y843050D03*
Y875050D03*
X994499Y941550D03*
X993999Y934550D03*
X994499Y956050D03*
Y973550D03*
X993999Y993050D03*
Y1012050D03*
X994999Y1033050D03*
Y1045050D03*
X998599Y1110950D03*
Y1096450D03*
Y1128450D03*
X998099Y1147950D03*
Y1166950D03*
X999099Y1187950D03*
Y1214450D03*
Y1199950D03*
Y1231950D03*
X998599Y1251450D03*
Y1270450D03*
X999599Y1291450D03*
X996500Y1324800D03*
X1000700Y1358100D03*
X994200Y1421500D03*
X1008999Y1702450D03*
X1008599Y1716050D03*
X994999Y1748950D03*
X999999Y1775250D03*
X1009999Y1797450D03*
X993499Y1805550D03*
X1007599Y1818450D03*
X993499Y1824550D03*
X1003599Y1846650D03*
X993499Y1833550D03*
X1011299Y1860650D03*
X995699Y1858950D03*
X1001599Y1921450D03*
X1000999Y1946350D03*
X1002500Y1953500D03*
X1005000Y1980500D03*
X994999Y1986550D03*
X1022000Y15500D03*
X1020499Y50550D03*
X1020999Y33050D03*
Y70050D03*
Y85550D03*
Y105050D03*
X1020499Y122550D03*
X1020999Y158550D03*
X1021499Y141050D03*
Y178050D03*
Y193550D03*
Y213050D03*
X1020999Y230550D03*
Y252050D03*
X1020499Y269550D03*
X1020999Y304550D03*
Y289050D03*
Y324050D03*
X1020499Y341550D03*
Y391550D03*
X1020999Y374050D03*
Y411050D03*
Y426550D03*
Y446050D03*
X1020499Y463550D03*
X1021999Y486550D03*
X1021499Y504050D03*
X1021999Y539050D03*
Y523550D03*
Y558550D03*
X1021499Y576050D03*
X1020499Y623050D03*
X1020999Y605550D03*
Y642550D03*
Y658050D03*
Y677550D03*
X1020499Y695050D03*
X1020999Y720050D03*
X1020499Y737550D03*
X1020999Y772550D03*
Y757050D03*
Y792050D03*
X1020499Y809550D03*
Y828050D03*
X1019999Y845550D03*
X1020499Y865050D03*
Y880550D03*
X1019999Y917550D03*
X1020499Y900050D03*
X1019999Y934050D03*
X1019499Y951550D03*
X1019999Y971050D03*
Y986550D03*
X1019499Y1023550D03*
X1019999Y1006050D03*
Y1043050D03*
Y1058550D03*
X1020499Y1081550D03*
X1019999Y1099050D03*
X1020499Y1118550D03*
Y1134050D03*
X1019499Y1146050D03*
X1018999Y1163550D03*
X1019499Y1183050D03*
Y1198550D03*
X1016999Y1219050D03*
X1016499Y1236550D03*
X1016999Y1256050D03*
Y1271550D03*
X1016499Y1301050D03*
X1022599Y1322950D03*
X1023300Y1344400D03*
X1024300Y1365200D03*
Y1393600D03*
X1022299Y1715750D03*
X1016899Y1731650D03*
X1020299Y1746650D03*
X1015299Y1765950D03*
X1026899Y1768550D03*
X1022999Y1784550D03*
X1022499Y1802050D03*
X1022999Y1821550D03*
Y1837050D03*
X1020999Y1860050D03*
X1020499Y1877550D03*
X1020999Y1912550D03*
Y1897050D03*
X1017499Y1954550D03*
X1017999Y1937050D03*
X1023000Y1973000D03*
X1017999Y1987050D03*
G54D22*
G01X1004307Y1626102D02*
X988302D01*
X987100Y1624900D01*
G01X981200Y1625800D02*
X986198Y1630798D01*
X991710D01*
X992014Y1631102D01*
X1004307D01*
G54D13*
X29531Y309549D03*
Y1029510D03*
X17720Y1903132D03*
X129921Y17716D03*
X271657Y267699D03*
Y673210D03*
Y1078722D03*
Y1484234D03*
Y1889746D03*
X994098Y149588D03*
Y673210D03*
Y1068880D03*
X994093Y1889751D03*
G54D23*
G01X155999Y181050D02*
X140999D01*
X122999Y199050D01*
X97999D01*
G01X194700Y1385700D02*
X194151D01*
X192999Y1386852D01*
Y1435550D01*
X223029Y1465580D01*
G01X229025Y1471576D02*
X260999Y1503550D01*
G01X223029Y1465580D02*
X229025Y1471576D01*
G01X223436Y1890465D02*
Y1929395D01*
X223662Y1929621D01*
Y1937713D01*
X226999Y1941050D01*
G54D14*
X12569Y391726D03*
Y387789D03*
Y383852D03*
Y379915D03*
Y375978D03*
Y372041D03*
Y411411D03*
Y407474D03*
Y403537D03*
Y399600D03*
Y395663D03*
Y431098D03*
Y427161D03*
Y423223D03*
Y454720D03*
Y450783D03*
Y446846D03*
Y442909D03*
Y438972D03*
Y435035D03*
Y474405D03*
Y470468D03*
Y466531D03*
Y462594D03*
Y458657D03*
Y494090D03*
Y490153D03*
Y486216D03*
Y482279D03*
Y478342D03*
Y517712D03*
Y513775D03*
Y509838D03*
Y505901D03*
Y501964D03*
Y498027D03*
Y537397D03*
Y533460D03*
Y529523D03*
Y525586D03*
Y521649D03*
Y561019D03*
Y557082D03*
Y553145D03*
Y549208D03*
Y545271D03*
Y541334D03*
Y580704D03*
Y576767D03*
Y572830D03*
Y568893D03*
Y564956D03*
Y600389D03*
Y596452D03*
Y592515D03*
Y584641D03*
Y588578D03*
Y624011D03*
Y620074D03*
Y616137D03*
Y612200D03*
Y604326D03*
Y608263D03*
Y643696D03*
Y639759D03*
Y635822D03*
Y631885D03*
Y627948D03*
Y663381D03*
Y659444D03*
Y655507D03*
Y651570D03*
Y647633D03*
Y687003D03*
Y683066D03*
Y679129D03*
Y675192D03*
Y671255D03*
Y667318D03*
Y698814D03*
Y694877D03*
Y690940D03*
X12560Y793325D03*
Y789388D03*
Y785451D03*
Y781514D03*
Y813010D03*
Y809073D03*
Y805136D03*
Y801199D03*
Y797262D03*
Y820884D03*
Y816947D03*
Y832696D03*
Y856318D03*
Y852381D03*
Y848444D03*
Y844507D03*
Y840570D03*
Y836633D03*
X12569Y1364167D03*
Y1360230D03*
Y1356293D03*
Y1383852D03*
Y1379915D03*
Y1375978D03*
Y1372041D03*
Y1368104D03*
Y1395663D03*
Y1391726D03*
Y1387789D03*
Y1427161D03*
Y1423224D03*
Y1419287D03*
Y1415350D03*
Y1411413D03*
Y1407475D03*
Y1446846D03*
Y1442909D03*
Y1438972D03*
Y1435035D03*
Y1431098D03*
Y1470468D03*
Y1466531D03*
Y1462594D03*
Y1458657D03*
Y1454720D03*
Y1450783D03*
Y1490153D03*
Y1486216D03*
Y1482279D03*
Y1478342D03*
Y1474405D03*
Y1509838D03*
Y1505901D03*
Y1501964D03*
Y1498027D03*
Y1494090D03*
Y1533460D03*
Y1529523D03*
Y1525586D03*
Y1521649D03*
Y1517712D03*
Y1513775D03*
Y1553145D03*
Y1549208D03*
Y1545271D03*
Y1541334D03*
Y1537397D03*
Y1568893D03*
Y1572830D03*
Y1564956D03*
Y1561019D03*
Y1557082D03*
Y1596452D03*
Y1588578D03*
Y1592515D03*
Y1584641D03*
Y1580704D03*
Y1576767D03*
Y1616137D03*
Y1612200D03*
Y1608263D03*
Y1604326D03*
Y1600389D03*
Y1639759D03*
Y1635822D03*
Y1631885D03*
Y1627948D03*
Y1624011D03*
Y1620074D03*
Y1659444D03*
Y1655507D03*
Y1651570D03*
Y1647633D03*
Y1643696D03*
Y1679129D03*
Y1675192D03*
Y1671255D03*
Y1667318D03*
Y1663381D03*
Y1683066D03*
X12560Y1765766D03*
Y1785451D03*
Y1781514D03*
Y1777577D03*
Y1773640D03*
Y1769703D03*
Y1805136D03*
Y1801199D03*
Y1797262D03*
Y1793325D03*
Y1789388D03*
Y1828759D03*
Y1824822D03*
Y1820885D03*
Y1816948D03*
Y1840570D03*
Y1836633D03*
Y1832696D03*
G54D24*
G01X12379Y309549D02*
X29531D01*
G01X17720Y1885980D02*
Y1903132D01*
G01D02*
Y1920284D01*
G01X29531Y292397D02*
Y309549D01*
G01D02*
Y326701D01*
G01Y309549D02*
X46683D01*
G01X68898Y12645D02*
Y17047D01*
G01D02*
Y21449D01*
G01X62346Y17047D02*
X68898D01*
G01D02*
X75450D01*
G01X68898Y185873D02*
Y190275D01*
G01D02*
Y194677D01*
G01Y190275D02*
X75450D01*
G01X68898Y418157D02*
Y422559D01*
G01D02*
Y426961D01*
G01X62346Y422559D02*
X68898D01*
G01D02*
X75450D01*
G01X68898Y1634693D02*
Y1639095D01*
G01D02*
Y1643497D01*
G01Y1639095D02*
X75450D01*
G01X112769Y17716D02*
X129921D01*
G01D02*
Y34868D01*
G01Y17716D02*
X147073D01*
G01X167323Y175401D02*
Y179803D01*
G01D02*
Y184205D01*
G01X160771Y179803D02*
X167323D01*
G01D02*
X173875D01*
G01X167323Y348629D02*
Y353031D01*
G01D02*
Y357433D01*
G01X160771Y353031D02*
X167323D01*
G01D02*
X173875D01*
G01X167323Y580913D02*
Y585315D01*
G01D02*
Y589717D01*
G01X160771Y585315D02*
X167323D01*
G01D02*
X173875D01*
G01X167323Y754141D02*
Y758543D01*
G01D02*
Y762945D01*
G01X160771Y758543D02*
X167323D01*
G01D02*
X173875D01*
G01X167323Y1565165D02*
Y1569567D01*
G01D02*
Y1573969D01*
G01X160771Y1569567D02*
X167323D01*
G01D02*
X173875D01*
G01X167323Y1797449D02*
Y1801851D01*
G01D02*
Y1806253D01*
G01X160771Y1801851D02*
X167323D01*
G01D02*
X173875D01*
G01X167323Y1970677D02*
Y1975079D01*
G01D02*
Y1979481D01*
G01X160771Y1975079D02*
X167323D01*
G01D02*
X173875D01*
G01X271657Y250547D02*
Y267699D01*
G01D02*
Y284851D01*
G01X254505Y267699D02*
X271657D01*
G01D02*
X288809D01*
G01X271657Y656058D02*
Y673210D01*
G01D02*
Y690362D01*
G01X254505Y673210D02*
X271657D01*
G01D02*
X288809D01*
G01X271657Y1061570D02*
Y1078722D01*
G01D02*
Y1095874D01*
G01X254505Y1078722D02*
X271657D01*
G01D02*
X288809D01*
G01X271657Y1467082D02*
Y1484234D01*
G01D02*
Y1501386D01*
G01X254505Y1484234D02*
X271657D01*
G01D02*
X288809D01*
G01X271657Y1872594D02*
Y1889746D01*
G01D02*
Y1906898D01*
G01X254505Y1889746D02*
X271657D01*
G01X895669Y175401D02*
Y179803D01*
G01D02*
Y184205D01*
G01X889117Y179803D02*
X895669D01*
G01D02*
X902221D01*
G01X895669Y348629D02*
Y353031D01*
G01D02*
Y357433D01*
G01X889117Y353031D02*
X895669D01*
G01D02*
X902221D01*
G01X895669Y580913D02*
Y585315D01*
G01D02*
Y589717D01*
G01X889117Y585315D02*
X895669D01*
G01D02*
X902221D01*
G01X895669Y754141D02*
Y758543D01*
G01D02*
Y762945D01*
G01X889117Y758543D02*
X895669D01*
G01D02*
X902221D01*
G01X895669Y986425D02*
Y990827D01*
G01D02*
Y995229D01*
G01X889117Y990827D02*
X895669D01*
G01D02*
X902221D01*
G01X895669Y1159653D02*
Y1164055D01*
G01D02*
Y1168457D01*
G01X889117Y1164055D02*
X895669D01*
G01D02*
X902221D01*
G01X895669Y1391937D02*
Y1396339D01*
G01D02*
Y1400741D01*
G01X889117Y1396339D02*
X895669D01*
G01D02*
X902221D01*
G01X895669Y1565165D02*
Y1569567D01*
G01D02*
Y1573969D01*
G01X889117Y1569567D02*
X895669D01*
G01D02*
X902221D01*
G01X895669Y1797449D02*
Y1801851D01*
G01D02*
Y1806253D01*
G01X889117Y1801851D02*
X895669D01*
G01D02*
X902221D01*
G01X895669Y1970677D02*
Y1975079D01*
G01D02*
Y1979481D01*
G01X889117Y1975079D02*
X895669D01*
G01D02*
X902221D01*
G01X976946Y149588D02*
X994098D01*
G01X976946Y673210D02*
X994098D01*
G01X976946Y1068880D02*
X994098D01*
G01X976941Y1889751D02*
X994093D01*
G01X994098Y132436D02*
Y149588D01*
G01D02*
Y166740D01*
G01Y149588D02*
X1011250D01*
G01X994098Y656058D02*
Y673210D01*
G01D02*
Y690362D01*
G01Y673210D02*
X1011250D01*
G01X994098Y1051728D02*
Y1068880D01*
G01D02*
Y1086032D01*
G01Y1068880D02*
X1011250D01*
G01X994093Y1872599D02*
Y1889751D01*
G01D02*
Y1906903D01*
G01Y1889751D02*
X1011245D01*
G54D15*
X14999Y1936050D03*
Y1940050D03*
X8499Y1937550D03*
X15099Y1944050D03*
X5303Y1947050D03*
X11703Y1951946D03*
X17499Y1961050D03*
X29699Y388484D03*
X29599Y382884D03*
X23399Y373931D03*
Y389679D03*
X23499Y381831D03*
X26299Y383854D03*
Y387629D03*
X28100Y374000D03*
X26299Y399601D03*
Y403376D03*
X29999Y398684D03*
X29899Y404384D03*
X23799Y405684D03*
X23499Y397579D03*
X35900Y412600D03*
X26524Y426720D03*
X26399Y423322D03*
X28672Y429356D03*
X29365Y421169D03*
X23399Y429051D03*
X28900Y417800D03*
X26492Y439350D03*
X26599Y442749D03*
X26899Y454850D03*
X28700Y451900D03*
X28800Y436700D03*
X28700Y445700D03*
X23399Y444799D03*
X23499Y452699D03*
Y436951D03*
X26799Y458497D03*
X26486Y462648D03*
X26499Y466250D03*
X29500Y460800D03*
X23499Y468447D03*
X23399Y476295D03*
Y460547D03*
X26299Y478404D03*
X26515Y481798D03*
X23399Y492043D03*
X23499Y484195D03*
X36499Y517775D03*
X26399Y501966D03*
Y505741D03*
X28600Y508500D03*
X38400Y514955D03*
X28664Y499429D03*
X23499Y515691D03*
Y499943D03*
X23399Y507791D03*
X36499Y521550D03*
X35338Y524746D03*
X26691Y532701D03*
X22800Y539600D03*
X23399Y523539D03*
X23499Y531439D03*
X26599Y525648D03*
Y529302D03*
X27199Y539600D03*
X39217Y554750D03*
X33307Y557938D03*
X26199Y547176D03*
X29999Y557150D03*
X33699Y561850D03*
X36499Y566350D03*
X22699Y577950D03*
X22999Y565550D03*
X28000Y578500D03*
X25581Y567763D03*
X27699Y573750D03*
X22978Y588571D03*
X28808Y593150D03*
X28700Y596549D03*
X27499Y620203D03*
Y623857D03*
X37999Y611550D03*
X26869Y616861D03*
X23499Y618053D03*
X23999Y609250D03*
X34976Y619250D03*
X26800Y611500D03*
X32200Y603710D03*
X31598Y607102D03*
X39600Y626984D03*
X38300Y633800D03*
X30712Y624971D03*
X29999Y640550D03*
X29819Y634951D03*
X23399Y641649D03*
X23799Y625950D03*
X23499Y633801D03*
X26568Y635950D03*
Y639604D03*
X30999Y656250D03*
Y650550D03*
X23499Y665297D03*
Y649549D03*
X23725Y657471D03*
X26737Y651957D03*
X26999Y656550D03*
X23699Y673150D03*
X23499Y681045D03*
X27687Y667447D03*
Y671101D03*
X27700Y682700D03*
X29999Y694550D03*
X25999Y694870D03*
X23999Y689050D03*
X27299Y783550D03*
X35300Y789375D03*
X32800Y803050D03*
X37416Y799033D03*
X37099Y811350D03*
X26299Y815050D03*
X35559Y795112D03*
X31699Y814350D03*
X37216Y807951D03*
X39649Y822000D03*
X29299Y836901D03*
X40400Y840792D03*
X22500Y853700D03*
X29600Y854000D03*
X23299Y863050D03*
X26662Y861550D03*
X25000Y858100D03*
X20400Y1048300D03*
X20999Y1320550D03*
X23700Y1354600D03*
X20999Y1352050D03*
X25000Y1357742D03*
X22851Y1374169D03*
X22999Y1366050D03*
X23499Y1381550D03*
X25507Y1372045D03*
X25558Y1368447D03*
X32550Y1392777D03*
X27499Y1387550D03*
X24499Y1389663D03*
X28499Y1391050D03*
X32333Y1389383D03*
X30500Y1395500D03*
X33321Y1414755D03*
X29786Y1414858D03*
X23499Y1421550D03*
X23999Y1413550D03*
X32451Y1411468D03*
X28999Y1411550D03*
X32094Y1448448D03*
X28697Y1448296D03*
X36198Y1446749D03*
X27099Y1444350D03*
X30999Y1438050D03*
X27999Y1430050D03*
X23499Y1445050D03*
X22999Y1437050D03*
X23999Y1429050D03*
X33206Y1432352D03*
X30499Y1434550D03*
X30378Y1462518D03*
X33915Y1462681D03*
X29069Y1459379D03*
X36791Y1460866D03*
X23028Y1468579D03*
X23499Y1460550D03*
X22999Y1453050D03*
X34465Y1481683D03*
X30999Y1482050D03*
X32520Y1485092D03*
X28999Y1478050D03*
X23599Y1476350D03*
X23277Y1484050D03*
X34099Y1497550D03*
X30499D03*
X27499Y1495050D03*
X36999Y1494550D03*
X22999Y1500050D03*
X23799Y1508050D03*
X24499Y1492050D03*
X30115Y1511900D03*
X33512Y1512051D03*
X29631Y1533063D03*
X31999Y1517846D03*
Y1521500D03*
X35245Y1522512D03*
X35999Y1514550D03*
X29765Y1515282D03*
X24423Y1527123D03*
X22999Y1515550D03*
X37999Y1530900D03*
X24199Y1523700D03*
X25247Y1546912D03*
X38500Y1534600D03*
X32099Y1535550D03*
X26705Y1534795D03*
X30199Y1545450D03*
X36340Y1558809D03*
X34896Y1555730D03*
X38208Y1569841D03*
X25521Y1563350D03*
X30520Y1572049D03*
X24999Y1569550D03*
X31149Y1568300D03*
X23608Y1572653D03*
X24323Y1559950D03*
X27123Y1572205D03*
X39000Y1573500D03*
X34999Y1595350D03*
X22699Y1594224D03*
X31099Y1595350D03*
X28899Y1613524D03*
X32299D03*
X26999Y1610550D03*
X34884Y1615734D03*
X23499Y1618050D03*
Y1610050D03*
Y1602050D03*
X33599Y1600200D03*
X29499Y1630050D03*
X32199Y1633124D03*
X34816Y1630953D03*
X22999Y1626050D03*
X23499Y1634050D03*
X32663Y1628181D03*
X31999Y1661127D03*
X28600Y1661039D03*
X29626Y1645002D03*
X33026Y1645051D03*
X27499Y1657050D03*
X32989Y1648451D03*
X26785Y1642089D03*
X23499Y1657050D03*
X23999Y1649550D03*
X23415Y1641634D03*
X34699Y1663300D03*
X22999Y1665550D03*
X24244Y1681868D03*
X22864Y1673550D03*
X32700Y1673300D03*
X32494Y1669706D03*
X29100Y1669500D03*
X30500Y1697500D03*
X39900Y1751200D03*
X41200Y1747050D03*
X30274Y1787238D03*
X35675Y1783450D03*
X39324Y1780623D03*
X38094Y1785840D03*
X38878Y1799571D03*
X34599Y1805123D03*
X37699Y1789850D03*
X37574Y1794050D03*
X31811Y1790271D03*
X40478Y1795820D03*
X32099Y1797150D03*
X28550Y1828153D03*
X29899Y1821050D03*
X34099Y1822850D03*
X35876Y1812350D03*
X34129Y1815267D03*
X36532Y1825352D03*
X36399Y1828750D03*
X26099Y1824950D03*
X29599Y1844350D03*
X22099Y1836609D03*
X28123Y1831527D03*
X25999Y1842550D03*
X39699Y1833850D03*
X28799Y1919060D03*
X23030Y1922038D03*
X26765Y1921945D03*
X34799Y1946750D03*
X38703Y1946754D03*
X25499Y1956050D03*
X32999Y1960555D03*
X31799Y1979050D03*
X41999Y200050D03*
X45800Y405200D03*
X61400Y452600D03*
X62497Y474346D03*
X60003Y534150D03*
X59999Y537550D03*
X42867Y548450D03*
X43099Y555850D03*
X46299Y552950D03*
X49799Y559150D03*
X42599Y567850D03*
X47543Y578340D03*
X44959Y575756D03*
X60076Y595777D03*
X55499Y595650D03*
X42202Y608195D03*
X41400Y611500D03*
X47626Y611300D03*
X45701Y607700D03*
X42709Y625607D03*
X41500Y642800D03*
X57800Y634300D03*
X44900Y642800D03*
X47101Y632355D03*
X41500Y635000D03*
X52500D03*
X48999Y642900D03*
X50410Y695801D03*
X50300Y699200D03*
X45100Y793100D03*
X44046Y799554D03*
X46887Y803413D03*
X51100Y806300D03*
X49900Y813200D03*
X56281Y801350D03*
X50399Y836250D03*
X46700Y820100D03*
X54074Y815750D03*
X62405Y820300D03*
X46576Y832951D03*
X48346Y844529D03*
X58699Y837250D03*
X44697Y1546793D03*
X44299Y1550950D03*
X42199Y1601050D03*
X47400Y1721700D03*
X42000Y1740100D03*
X47717Y1731337D03*
X47800Y1740500D03*
X45877Y1728477D03*
Y1724823D03*
X47000Y1737100D03*
X43600D03*
X42275Y1754000D03*
X45799Y1757650D03*
X47440Y1761391D03*
X47400Y1765250D03*
X43751Y1780559D03*
X46999Y1779550D03*
X46199Y1783050D03*
X43925Y1767890D03*
X47604Y1769005D03*
X45782Y1771877D03*
X47499Y1775350D03*
X47899Y1798650D03*
X48049Y1791450D03*
X42199Y1792250D03*
X46799Y1794900D03*
X61009Y1822340D03*
X60449Y1842550D03*
X46499Y1836550D03*
X47166Y1839884D03*
X43099Y1833850D03*
X57999Y1891050D03*
X42499Y1902550D03*
X48499Y1897050D03*
X44368Y1951450D03*
X44399Y1942250D03*
X42532Y1946783D03*
X53999Y1946650D03*
X50299D03*
X46565Y1946703D03*
X45999Y1971450D03*
X50499Y1961550D03*
X43462Y1961160D03*
X78700Y74200D03*
Y70700D03*
X74999Y70550D03*
Y74050D03*
X74499Y80650D03*
Y84050D03*
X65999Y216050D03*
X65000Y455500D03*
X62503Y470946D03*
X66199Y475184D03*
Y469884D03*
X77499Y469550D03*
X62978Y486217D03*
X63067Y489616D03*
X66299Y490784D03*
Y485484D03*
X77999Y493050D03*
X77499Y502550D03*
X65599Y514250D03*
X63499Y538550D03*
Y533050D03*
X68000Y546500D03*
X72500Y545000D03*
X81251Y607249D03*
Y619251D03*
X82499Y627050D03*
X80499Y664550D03*
X74499Y662050D03*
X78499Y654050D03*
X76999Y664550D03*
X81999Y668050D03*
X65500Y817700D03*
X80500Y817000D03*
X76540Y850938D03*
X75500Y847700D03*
X68860Y838706D03*
X69499Y842950D03*
X63499Y843050D03*
X74220Y854150D03*
X72362Y849550D03*
X80699Y1004450D03*
Y1000450D03*
X72000Y1013400D03*
X63273Y1023974D03*
X66499Y1025050D03*
X75500Y1012261D03*
X65486Y1031515D03*
X80000Y1090500D03*
X74500Y1097550D03*
X79899Y1104550D03*
X74399Y1111550D03*
X76999Y1196550D03*
X78499Y1273550D03*
X78613Y1282664D03*
X78779Y1302664D03*
Y1312664D03*
X77758Y1357742D03*
X76000Y1431100D03*
X80043Y1544691D03*
X78600Y1561900D03*
X75000Y1561800D03*
X74400Y1574800D03*
X80400Y1571766D03*
X82329Y1568117D03*
X79000Y1555500D03*
X82429D03*
X74800Y1584700D03*
X78100Y1688189D03*
X74500Y1692000D03*
X74400Y1778100D03*
X80099Y1817250D03*
X80999Y1836550D03*
X93999Y58550D03*
X92900Y66128D03*
X92999Y86128D03*
X97499Y90050D03*
X92999Y96128D03*
X89603Y132629D03*
X86899Y130567D03*
X86599Y126750D03*
X95350Y204550D03*
X89800Y208550D03*
X96900Y510000D03*
X93200Y510500D03*
X95500Y513400D03*
X98900D03*
X83700Y529500D03*
X88999Y538050D03*
X104502Y530552D03*
X86199Y536025D03*
Y532250D03*
X89000Y816500D03*
X90000Y826000D03*
X90500Y831500D03*
X98700Y822550D03*
X98000Y833500D03*
X98700Y842600D03*
X92999Y868550D03*
X92499Y876550D03*
X94999Y901550D03*
X89469Y935588D03*
X85999Y940429D03*
X86399Y937050D03*
X89499Y942850D03*
X102100Y968500D03*
X99000Y965000D03*
X104600Y980500D03*
X90000Y993100D03*
X92600Y996100D03*
X88000Y1008500D03*
X101499Y1072550D03*
X103999Y1216863D03*
X102900Y1196050D03*
X103686Y1223863D03*
X101541Y1262607D03*
X101399Y1292550D03*
X102700Y1321363D03*
X102000Y1341000D03*
X91279Y1340642D03*
X86165Y1339050D03*
X86890Y1342860D03*
X101500Y1352000D03*
X89999Y1348050D03*
X86890Y1346635D03*
X102350Y1344500D03*
Y1348154D03*
X97229Y1373337D03*
X97000Y1377600D03*
X98599Y1491350D03*
X100699Y1471050D03*
X100499Y1479650D03*
X83932Y1544705D03*
X100800Y1536450D03*
X96200Y1550100D03*
X99899Y1539850D03*
X100000Y1546650D03*
X90324Y1538800D03*
X97499Y1554550D03*
X98144Y1534309D03*
X96999Y1558050D03*
X89373Y1561073D03*
X85600Y1561500D03*
X95499Y1665418D03*
X92900Y1678176D03*
X93999Y1703050D03*
X92873Y1708176D03*
X92479Y1718176D03*
X89306Y1746856D03*
X89499Y1753575D03*
X85341Y1752245D03*
X85194Y1748848D03*
X99199Y1761899D03*
X99999Y1753575D03*
X101399Y1784700D03*
X85599Y1797350D03*
X96600Y1826000D03*
X86649Y1817100D03*
X90000Y1827900D03*
X93500D03*
X97999Y1843050D03*
X112999Y124050D03*
X111790Y132259D03*
X115876Y125973D03*
Y130050D03*
X114900Y177900D03*
X122397Y252688D03*
X122799Y249150D03*
X124999Y246050D03*
X123378Y255944D03*
X107499Y497050D03*
X107526Y528996D03*
X109400Y543200D03*
X106000D03*
X105100Y600000D03*
X107000Y604800D03*
X125499Y635550D03*
Y638950D03*
X124999Y643050D03*
X110500Y790200D03*
X111100Y813400D03*
X111200Y799450D03*
X111207Y810001D03*
X110700Y795700D03*
X111089Y806603D03*
X110800Y803100D03*
X110499Y834550D03*
X106749Y934367D03*
X108441Y924705D03*
X108845Y931657D03*
X109099Y928250D03*
X108200Y963600D03*
X107300Y986000D03*
X107400Y992900D03*
X124100Y1047100D03*
X123999Y1054050D03*
Y1050650D03*
X120100Y1053200D03*
X116700Y1063500D03*
X112699Y1058974D03*
X105499Y1080550D03*
X106718Y1076050D03*
X105999Y1085800D03*
X121500Y1083600D03*
X121100Y1075300D03*
X117499Y1079300D03*
X105600Y1069500D03*
X124423Y1077523D03*
Y1081177D03*
X120749Y1093990D03*
X125900Y1091282D03*
X116249Y1102550D03*
X112999Y1103740D03*
X123999Y1102550D03*
X108999Y1102050D03*
X106999Y1194550D03*
X106162Y1205702D03*
X114999Y1210363D03*
X118999Y1219050D03*
X123970Y1221573D03*
X119399Y1298113D03*
X116999Y1288050D03*
X120507Y1317050D03*
X111499Y1311800D03*
X107999Y1307713D03*
X116499Y1328013D03*
X120507Y1328096D03*
X113000Y1341000D03*
X107228Y1330552D03*
X107500Y1340500D03*
X109228Y1337090D03*
Y1333315D03*
X119499Y1339050D03*
X113500Y1352000D03*
X110499Y1365050D03*
X109999Y1355050D03*
X112440Y1358196D03*
X112999Y1361550D03*
X121000Y1364000D03*
X113500Y1344500D03*
Y1348154D03*
X125100Y1366000D03*
X117390Y1426201D03*
X119507Y1423540D03*
X117390Y1429976D03*
X104935Y1440634D03*
X104999Y1444941D03*
X107328Y1438218D03*
X114499Y1432050D03*
X107999Y1448050D03*
X124290Y1469241D03*
X123808Y1465050D03*
X106999Y1454450D03*
X105099Y1459150D03*
X123999Y1473050D03*
X122199Y1476050D03*
X118499Y1694050D03*
X117499Y1706050D03*
X109499Y1712213D03*
X104999Y1708963D03*
X117249Y1712090D03*
X112753Y1716613D03*
X122642Y1704243D03*
X112562Y1720613D03*
X123749Y1711550D03*
X109499Y1743550D03*
X107499Y1736550D03*
X109399Y1739550D03*
X106999Y1746290D03*
X110099Y1759875D03*
X123393Y1870859D03*
X123592Y1874254D03*
X127999Y157050D03*
X147099Y245350D03*
X141499Y427550D03*
Y423050D03*
X135499Y517550D03*
X138999Y524213D03*
X137899Y545451D03*
X138416Y553500D03*
X140940Y561800D03*
X141300Y565900D03*
X127999Y645550D03*
X131400Y644600D03*
X144238Y645356D03*
X128725Y636626D03*
X128479Y640589D03*
X141773Y643013D03*
X144238Y649131D03*
X140499Y649350D03*
X134300Y646400D03*
X141500Y711000D03*
X137100Y1084800D03*
X140800Y1076300D03*
X137481Y1077557D03*
X137477Y1081177D03*
X132499Y1094550D03*
X138600Y1124600D03*
X130699Y1210653D03*
X135850Y1322250D03*
X125999Y1315550D03*
X132999Y1319550D03*
X142667Y1319218D03*
X143700Y1332500D03*
X133475Y1331200D03*
X140000Y1332600D03*
X138000Y1359025D03*
X129000Y1356500D03*
X142999Y1456373D03*
X139815Y1454438D03*
X139235Y1460973D03*
X127898Y1462441D03*
X142900Y1460000D03*
X133090Y1699959D03*
X128749Y1703300D03*
X131999Y1710050D03*
X141500Y1715500D03*
X135499Y1710150D03*
X141999Y1764550D03*
X137999Y1861497D03*
Y1865151D03*
X141101Y1866545D03*
X140999Y1859550D03*
X135999Y1881550D03*
X152499Y149550D03*
X154200Y168500D03*
X149400Y166400D03*
X149999Y243504D03*
Y239729D03*
X157440Y283924D03*
Y303924D03*
Y313924D03*
X165699Y428050D03*
X153459Y427494D03*
X154101Y445550D03*
X159600Y446399D03*
X163549Y517100D03*
X152000Y520813D03*
X163449Y521650D03*
X149000Y537500D03*
X150500Y545000D03*
X160932Y549468D03*
X150750Y540416D03*
X156500Y554000D03*
X157000Y573851D03*
X160824Y577000D03*
X161000Y639100D03*
X158885Y679436D03*
Y689436D03*
X158385Y719436D03*
X159500Y814700D03*
X165499Y815550D03*
X153500Y834600D03*
X154799Y838050D03*
X153499Y918550D03*
X163500Y937100D03*
X160399Y922850D03*
X152500Y960000D03*
X154749Y979149D03*
Y968249D03*
X164700Y1085400D03*
X159000Y1083000D03*
X157700Y1114948D03*
X157600Y1124948D03*
X149562Y1315987D03*
X147400Y1321600D03*
X148024Y1333525D03*
X150338Y1453958D03*
X152499Y1462940D03*
X157440Y1490460D03*
Y1500460D03*
Y1520460D03*
Y1530460D03*
X157400Y1596550D03*
X160200Y1598500D03*
X165575Y1676975D03*
X152633Y1677967D03*
X150999Y1713550D03*
X165900Y1790500D03*
X161900Y1793400D03*
X159421Y1925972D03*
X175999Y82428D03*
X174999Y79050D03*
X175499Y86572D03*
X176399Y94872D03*
X178999Y79050D03*
X186999Y99050D03*
X169999Y129050D03*
X188999Y120800D03*
X173499Y149050D03*
X173500Y166315D03*
X187699Y492850D03*
X173100Y483100D03*
X172499Y491053D03*
X176799Y493850D03*
X188000Y484500D03*
X171722Y513827D03*
X182499Y532550D03*
X168453Y527949D03*
X183499Y556100D03*
X172660Y815731D03*
X169106Y815865D03*
X174199Y841050D03*
X172500Y919294D03*
X172000Y931600D03*
X171100Y935000D03*
X171000Y939500D03*
X172000Y961000D03*
X170250Y948500D03*
X179499Y1275550D03*
X181000Y1365500D03*
X180500Y1369900D03*
X179999Y1655887D03*
X171999Y1662250D03*
X169600Y1682300D03*
X169100Y1685800D03*
X174250Y1694500D03*
X181100Y1682700D03*
X177900Y1690400D03*
X205938Y72528D03*
X201499Y104550D03*
X205499Y105550D03*
X207999Y109550D03*
X197899Y165075D03*
X199900Y554050D03*
X193549Y575875D03*
X200000Y818000D03*
X200539Y890300D03*
X200799Y896600D03*
X198924Y975975D03*
X199149Y1362900D03*
X194700Y1385700D03*
X193500Y1647000D03*
X201499Y1781050D03*
X194049Y1792600D03*
X210605Y70692D03*
X210685Y74725D03*
X215138Y72559D03*
X210634Y66863D03*
X210638Y62959D03*
X225499Y68550D03*
X210738Y82159D03*
Y78459D03*
X230749Y76300D03*
X213499Y104650D03*
X223499Y108150D03*
X218499Y190550D03*
X225298Y281114D03*
X213499Y283864D03*
X214063Y318114D03*
X213400Y355300D03*
X224998Y357049D03*
X220000Y516400D03*
X216999Y686550D03*
X213999Y725050D03*
X230849Y726050D03*
X228999Y765550D03*
X218224Y765325D03*
X211750Y894600D03*
X229562Y904113D03*
X215499Y905550D03*
X221800Y1069300D03*
X221300Y1083238D03*
X229800Y1073600D03*
X226800Y1093400D03*
X224750Y1483950D03*
X229025Y1471576D03*
X227814Y1887513D03*
X223436Y1890465D03*
X229800Y1875700D03*
X218100Y1886400D03*
X214999Y1909550D03*
X213562Y1926113D03*
X220062Y1931113D03*
X213138Y1952703D03*
X210999Y1942050D03*
X246999Y51550D03*
X246499Y42550D03*
X246999Y69550D03*
Y60550D03*
X246499Y86050D03*
Y80550D03*
X245499Y100550D03*
X233749Y110800D03*
X237899Y107050D03*
X247800Y269700D03*
X250300Y275100D03*
X250400Y283100D03*
X239600Y278600D03*
X231800Y318414D03*
X233998Y357549D03*
X239400Y357400D03*
X246800Y677100D03*
X249700Y682500D03*
X238500Y680800D03*
X249800Y689900D03*
X252499Y726050D03*
X241600Y765700D03*
X236800Y765800D03*
X233500Y1066100D03*
X242000Y1066000D03*
X247500Y1085500D03*
X251500Y1136700D03*
X241000Y1469600D03*
X233700Y1481600D03*
X232650Y1493450D03*
X231800Y1887100D03*
X232314Y1890513D03*
X236225Y1883125D03*
X231999Y1914050D03*
X249600Y1896800D03*
X249499Y1928050D03*
X240964Y1934113D03*
X253999Y44050D03*
X253871Y291410D03*
X252935Y319114D03*
X254499Y697700D03*
X255000Y1125700D03*
X256000Y1133000D03*
X269500Y1135500D03*
X261999Y1516050D03*
X257499Y1911050D03*
X264499Y1964050D03*
X291999Y94050D03*
X282800Y87500D03*
X293999Y293550D03*
X284999Y338650D03*
X281499Y338550D03*
X294500Y339000D03*
X279939Y728610D03*
X285499Y745050D03*
X282099D03*
X292999Y743650D03*
X277039Y740300D03*
X282500Y1135000D03*
X295000Y1513000D03*
X289999Y1554650D03*
X293700Y1553351D03*
X276039Y1551300D03*
X283499Y1556050D03*
X279999D03*
X291400Y1561500D03*
X285499Y1930050D03*
X288709Y1948042D03*
X284999Y1947691D03*
X280689Y1942710D03*
X296099Y17100D03*
X305099Y17000D03*
X311400Y17100D03*
X308999Y87050D03*
X297499Y97550D03*
X315800Y100500D03*
X298800Y333000D03*
X301249Y346050D03*
X313039Y352350D03*
X308999Y716450D03*
X315999Y718950D03*
X298000Y743500D03*
X310999Y757050D03*
X314999Y1527550D03*
X297800Y1561600D03*
X312999Y1566050D03*
X310249Y1569800D03*
X313499Y1919050D03*
X310499Y1957050D03*
X315999Y1958550D03*
X317000Y17300D03*
X324800Y89400D03*
X323400Y105200D03*
X326499Y334054D03*
Y337454D03*
X321900Y364600D03*
X327999Y740550D03*
X323249Y749010D03*
X327749Y744050D03*
X324959Y766750D03*
X329499Y801550D03*
X330540Y795509D03*
X320499Y798050D03*
X326500Y1550200D03*
X324000Y1562500D03*
X330300Y1561200D03*
X323999Y1577250D03*
X325221Y1927272D03*
X331622Y1944767D03*
X329999Y1952273D03*
X332103Y1948133D03*
X327100Y1966472D03*
X343499Y31650D03*
X354999Y72050D03*
X343499Y60150D03*
X341499Y63050D03*
Y67110D03*
X357503Y77043D03*
X344520Y406329D03*
X350499Y597300D03*
Y715050D03*
X340699Y1046086D03*
X345499Y1096550D03*
X345424Y1310050D03*
X347324Y1524000D03*
X354500Y1559500D03*
X349774Y1582900D03*
X354000Y1584900D03*
X353499Y1710450D03*
X348499Y1762050D03*
X342999Y1947409D03*
X342621Y1943409D03*
X358999Y61550D03*
X374499Y77550D03*
X365499Y86550D03*
X371999Y549300D03*
X375999Y698550D03*
X371500Y880600D03*
X364499Y1099050D03*
X372999Y1123550D03*
X370149Y1320050D03*
X366149Y1554050D03*
X377900Y1703800D03*
X398799Y36152D03*
X381999Y50150D03*
X382339Y41610D03*
X381999Y53550D03*
X394199Y45050D03*
X381999Y57050D03*
X385999Y78050D03*
X400499Y406329D03*
X394649Y630600D03*
X390999Y1514398D03*
Y1517798D03*
X385499Y1735050D03*
X401499Y80550D03*
X402499Y1476850D03*
X400999Y1575550D03*
X645549Y1815134D03*
X644360Y1819137D03*
X659549Y1810634D03*
X690249Y1805634D03*
X707600Y1815600D03*
X711652Y1822109D03*
X711848Y1825504D03*
X732549Y1806634D03*
X733149Y1798634D03*
X733049Y1814134D03*
X752999Y746842D03*
X757499Y745342D03*
Y1079550D03*
X755600Y1149800D03*
X758499Y1371050D03*
X757999Y1484050D03*
X758199Y1553650D03*
X755000Y1825000D03*
X758499Y1893550D03*
X759114Y1957673D03*
X770999Y302050D03*
Y290050D03*
Y295550D03*
X763571Y295622D03*
X777999Y296050D03*
X772499Y323050D03*
X772873Y326924D03*
X760778Y345050D03*
X768178Y333964D03*
X780499Y330050D03*
X771105Y722789D03*
X766499Y732842D03*
X762999Y734550D03*
X769999Y733050D03*
X771999Y1124550D03*
X772499Y1130050D03*
X779499Y1131050D03*
X767083Y1134550D03*
X768199Y1138590D03*
X774542Y1530050D03*
X774577Y1533796D03*
X771225Y1539474D03*
X767936Y1540336D03*
X774500Y1788000D03*
X770999Y1820550D03*
X771499Y1936550D03*
X767999Y1945173D03*
X764908Y1946592D03*
X771499Y1940050D03*
X785499Y291050D03*
X786978Y298529D03*
X791499Y333050D03*
X789999Y336550D03*
X784499Y334050D03*
X781999Y725550D03*
X788999Y736050D03*
X791999Y733050D03*
X784939Y733550D03*
X792154Y1135926D03*
X784439Y1136550D03*
X789499Y1138050D03*
X784499Y1529050D03*
X784577Y1535628D03*
X791499Y1543550D03*
X793999Y1541050D03*
X788000Y1788000D03*
X793000Y1803500D03*
X795849Y1805500D03*
X791999Y1819050D03*
X783499Y1827050D03*
X802499Y1951550D03*
X800431Y1941193D03*
X785939Y1946800D03*
X792499Y1949050D03*
X794499Y1941050D03*
X782999Y1937050D03*
X802099Y1961950D03*
X820749Y163850D03*
X813249Y163800D03*
X821999Y193116D03*
X809940Y264940D03*
X822100Y261700D03*
Y279500D03*
X816700Y274300D03*
X820600Y664300D03*
X808660Y667540D03*
X813200Y675900D03*
X807000Y1072900D03*
X815400Y1078800D03*
X803199Y1151850D03*
X822100Y1466800D03*
X809960Y1478040D03*
X814700Y1486300D03*
X804899Y1556950D03*
X812000Y1799500D03*
X821249Y1791250D03*
X811000Y1793000D03*
X822499Y1815164D03*
X807000Y1822300D03*
X803500Y1822708D03*
X822700Y1871100D03*
X810900Y1882440D03*
X805900Y1887560D03*
X841499Y135550D03*
X827499Y163550D03*
X839249Y164050D03*
X829917Y216200D03*
X833576Y215432D03*
X837999Y219550D03*
X842499Y280924D03*
X827500Y274500D03*
X836500Y274950D03*
X827499Y313424D03*
X829800Y666650D03*
X835150Y677650D03*
X825700Y1083100D03*
X825800Y1072300D03*
X827700Y1487600D03*
X836625Y1487400D03*
X828500Y1877800D03*
X834799Y1946950D03*
X861999Y146550D03*
X854400Y264600D03*
X847878Y250040D03*
X851278Y249974D03*
X847450Y246666D03*
X850999Y246550D03*
X858478Y274050D03*
X865499Y288050D03*
X851172Y655432D03*
X847772Y655370D03*
X851197Y652032D03*
X847493Y651981D03*
X852696Y671197D03*
X850833Y1061441D03*
X847233Y1061492D03*
X847355Y1058094D03*
X851042Y1058047D03*
X852333Y1077716D03*
X860133Y1084142D03*
X864499Y1128750D03*
X860799Y1358925D03*
X861849Y1376050D03*
X848888Y1466402D03*
X852288Y1466346D03*
X848861Y1462463D03*
X852429Y1462948D03*
X854327Y1477550D03*
X858827Y1485696D03*
X863699Y1501250D03*
X862800Y1712700D03*
X851500Y1821400D03*
X849375Y1824982D03*
X854905Y1825583D03*
X853499Y1871036D03*
X850099Y1871056D03*
X854480Y1867578D03*
X849999Y1867550D03*
X863788Y1866953D03*
X865501Y1858747D03*
X859314Y1891365D03*
X854814Y1883550D03*
X863699Y1906450D03*
X857099Y1917650D03*
X882499Y147050D03*
X867500Y163924D03*
X867576Y159924D03*
X878078Y240103D03*
Y243878D03*
X874928Y238822D03*
X874790Y244748D03*
X871999Y283924D03*
X872136Y273924D03*
X886600Y303924D03*
X868799Y294750D03*
X867899Y321550D03*
X886200Y313924D03*
X868299Y336150D03*
X879750Y570550D03*
X879950Y565050D03*
X878596Y645573D03*
X874999Y644550D03*
X878596Y649348D03*
X875270Y650059D03*
X883083Y979183D03*
X879708Y971892D03*
X878233Y1051095D03*
X877964Y1054485D03*
X874733Y1055792D03*
X874999Y1049550D03*
X872086Y1084948D03*
X871999Y1094948D03*
X871499Y1124948D03*
X872086Y1114948D03*
X866700Y1379796D03*
X866596Y1375796D03*
X878054Y1456450D03*
X877853Y1459991D03*
X874499Y1460550D03*
X874986Y1454983D03*
X872086Y1490460D03*
X871999Y1500460D03*
Y1520460D03*
X872086Y1530460D03*
X867523Y1542821D03*
X867199Y1535150D03*
X886439Y1717600D03*
X873800Y1733600D03*
X879700Y1786300D03*
X879664Y1782213D03*
X866914Y1861840D03*
Y1865615D03*
X871921Y1905972D03*
X871421Y1895972D03*
X872086Y1925972D03*
Y1935972D03*
X901499Y92050D03*
X897555Y90494D03*
X898999Y99050D03*
X902499Y110550D03*
X898999D03*
X907499Y131800D03*
X896999Y141550D03*
X902999Y556050D03*
X900499Y962100D03*
X900999Y979050D03*
X889800Y1711500D03*
X923761Y85550D03*
X928561Y95181D03*
X928428Y83714D03*
X928508Y87747D03*
X928561Y91481D03*
X928457Y79885D03*
X928461Y75981D03*
X916499Y115050D03*
X926999D03*
Y122050D03*
X910999Y124550D03*
X916499Y172550D03*
X922049Y574375D03*
Y978575D03*
X921549Y1788475D03*
X917499Y1796550D03*
X932961Y85581D03*
X943499Y82550D03*
X930999Y115550D03*
X938499D03*
X946899Y122550D03*
X937999Y122050D03*
X934499Y118750D03*
X939549Y175175D03*
X961499Y93350D03*
X958999Y96050D03*
X961499Y100050D03*
X966499Y552050D03*
X965999Y954550D03*
X965150Y1639500D03*
X961702Y1636102D03*
X969600Y1638300D03*
X967600Y1651100D03*
X971558Y1646500D03*
X981200Y1618002D03*
X986400Y1639302D03*
X987100Y1624900D03*
X981200Y1625800D03*
X990425Y1633898D03*
X987029Y1634075D03*
X977500Y1660500D03*
X989502Y1646000D03*
X988800Y1658300D03*
X981500Y1653000D03*
X980800Y1659600D03*
X982050Y1649302D03*
X978000Y1668000D03*
X989000Y1663802D03*
X987200Y1675600D03*
X989900Y1678800D03*
X974000Y1670700D03*
X984211Y1667500D03*
G54D25*
G01X11069Y375978D02*
X18972D01*
X18978Y375984D01*
G03X20716Y376704I0J2458D01*
G01X20869Y376858D01*
G02X21899Y377284I1029J-1030D01*
G01X28990D01*
G02X30929Y376481I0J-2742D01*
G01X59429Y347981D01*
G02X59999Y346605I-1376J-1376D01*
G01Y246263D01*
G02X59750Y246014I-249J0D01*
G01X59749D01*
G03X59500Y245765I0J-249D01*
G01Y243863D01*
G03X59749Y243614I249J0D01*
G01X59750D01*
G02X59999Y243365I0J-249D01*
G01Y146237D01*
G03X61079Y143630I3687J0D01*
G01X82041Y122668D01*
G03X86671Y120750I4630J4630D01*
G01X94970D01*
G03X99352Y122564I1J6197D01*
G01X102668Y125880D01*
X102782Y125993D01*
G02X105815Y127250I3034J-3033D01*
G01X114599D01*
G02X115876Y125973I0J-1277D01*
G01X11069Y379915D02*
X19151D01*
X19157Y379921D01*
G02X20929Y379187I0J-2506D01*
G03X22385Y378584I1456J1456D01*
G01X28499D01*
G02X32196Y377052I-1J-5229D01*
G01X32222Y377027D01*
X60099Y349150D01*
G02X61299Y346253I-2897J-2897D01*
G01Y146238D01*
G03X61998Y144550I2387J0D01*
G01X62925Y143623D01*
X63249Y143300D01*
X82956Y123593D01*
G03X83157Y123402I3831J3831D01*
G03X86672Y122050I3516J3895D01*
G01X94970D01*
G03X98432Y123484I0J4896D01*
G01X101864Y126915D01*
G02X105814Y128550I3951J-3955D01*
G01X114366D01*
G03X114622Y128601I0J668D01*
G01X114754Y128656D01*
G03X115204Y128956I-530J1283D01*
G01X115576Y129328D01*
G03X115876Y130050I-721J723D01*
G01X11069Y391726D02*
X19494D01*
X19500Y391732D01*
G03X19889Y391893I0J550D01*
G01X20766Y392770D01*
G02X21399Y393032I633J-633D01*
G01X29209D01*
G02X32229Y391781I0J-4272D01*
G01X64952Y359058D01*
G02X67400Y353150I-5909J-5910D01*
G01X67399D01*
Y292519D01*
G03X69030Y288581I5568J-1D01*
G01X69029Y288580D01*
X122976Y234634D01*
X123099Y234509D01*
G03X129399Y231901I6297J6297D01*
G01Y231900D01*
X819160D01*
G03X824329Y234041I0J7310D01*
G01X839468Y249180D01*
X840354Y250064D01*
G02X841499Y250541I1148J-1144D01*
G01Y250540D01*
X846671D01*
G02X847878Y250040I0J-1707D01*
G01X11069Y395663D02*
X19664D01*
X19670Y395669D01*
G02X20539Y395309I0J-1229D01*
G01X21199Y394650D01*
G03X21967Y394332I768J768D01*
G01X29209D01*
G02X33149Y392700I0J-5572D01*
G01X65597Y360252D01*
X65871Y359979D01*
G02X68699Y353150I-6829J-6828D01*
G01Y292518D01*
G03X69949Y289500I4268J0D01*
G01X123899Y235550D01*
X124021Y235427D01*
G03X129399Y233200I5377J5378D01*
G01X819160D01*
G03X823409Y234960I0J6010D01*
G01X838549Y250100D01*
X839434Y250984D01*
G02X841499Y251840I2066J-2065D01*
G01X848580D01*
G02X850000Y251252I0J-2008D01*
G01X851278Y249974D01*
G01X11069Y407474D02*
X19829D01*
X19835Y407480D01*
G03X20849Y407900I0J1434D01*
G01X21449Y408500D01*
G02X22318Y408860I869J-869D01*
G01X34173D01*
G02X35329Y408381I0J-1635D01*
G01X74229Y369481D01*
G02X74799Y368105I-1376J-1376D01*
G01Y310638D01*
G03X76842Y305706I6975J0D01*
G01X125998Y256550D01*
X126114Y256433D01*
G02X126499Y255505I-928J-929D01*
G01Y252350D01*
G02X125499Y251350I-1000J0D01*
G01X123083D01*
G02X122598Y251551I0J686D01*
G02X122397Y252036I485J485D01*
G01Y252688D01*
G01X11069Y411411D02*
X11075Y411417D01*
X19947D01*
G02X21304Y410855I0J-1919D01*
G01X21504Y410655D01*
G03X22699Y410160I1195J1195D01*
G01X34174D01*
G02X36248Y409301I0J-2933D01*
G01X74948Y370601D01*
X74949D01*
X75149Y370401D01*
G02X75176Y370374I-2282J-2309D01*
G02X76099Y368106I-2324J-2267D01*
G01Y310286D01*
G03X77512Y306875I4824J0D01*
G01X126917Y257469D01*
X127018Y257367D01*
G02X127799Y255483I-1884J-1885D01*
G01Y252350D01*
G02X125499Y250050I-2300J0D01*
G01X124399D01*
G03X123204Y249555I0J-1690D01*
G01X122799Y249150D01*
G01X11069Y431098D02*
X19787D01*
X19793Y431104D01*
G03X20607Y431441I0J1151D01*
G01X21157Y431991D01*
G02X22154Y432404I997J-997D01*
G01X67583D01*
G02X70248Y431300I0J-3769D01*
G01X72698Y428850D01*
X73024Y428523D01*
G03X76099Y427250I3074J3075D01*
G01X80730D01*
G03X84455Y428793I0J5268D01*
G01X87355Y431693D01*
G02X88907Y432336I1552J-1552D01*
G01X276099D01*
G03X280296Y432766I-1J20709D01*
G03X280387Y432785I-4050J19624D01*
G03X283100Y433563I-4105J19433D01*
G01X283833Y433857D01*
X833339Y654720D01*
X834423Y655160D01*
G02X839299Y656300I4876J-9858D01*
G01X846842D01*
G02X847772Y655370I0J-930D01*
G01X28900Y417800D02*
X25778Y420922D01*
X25404D01*
X23999Y422327D01*
Y422701D01*
X23471Y423229D01*
X11075D01*
X11069Y423223D01*
G01Y435035D02*
X19410D01*
X19416Y435041D01*
G02X20811Y434463I0J-1973D01*
G01X21061Y434213D01*
G03X22290Y433704I1229J1229D01*
G01X67499D01*
G02X71228Y432160I1J-5273D01*
G01X71368Y432019D01*
X73918Y429469D01*
X73944Y429442D01*
G03X76099Y428550I2154J2155D01*
G01X81281D01*
G03X83145Y429322I0J2636D01*
G01X86336Y432513D01*
G02X89047Y433636I2711J-2711D01*
G01X276099D01*
G03X280120Y434048I1J19820D01*
G03X282747Y434823I-3365J16247D01*
G01X832854Y655926D01*
X832925Y655955D01*
X833847Y656326D01*
G02X839299Y657600I5452J-11029D01*
G01X847629D01*
G02X849976Y656628I0J-3319D01*
G01X851172Y655432D01*
G01X11069Y450783D02*
X19727D01*
X19733Y450789D01*
G02X20585Y450436I0J-1205D01*
G01X21135Y449886D01*
G03X22069Y449499I934J934D01*
G01X35923D01*
G03X40150Y451250I0J5978D01*
G01X49599Y460699D01*
X49600D01*
G02X53224Y462200I3623J-3623D01*
G01X174593D01*
G03X180254Y464545I0J8006D01*
G01X777376Y1061667D01*
G02X781299Y1063292I3923J-3923D01*
G01X847999D01*
G02X849677Y1062597I0J-2373D01*
G01X850833Y1061441D01*
G01X847233Y1061492D02*
G03X846962Y1061711I-1202J-1211D01*
G03X846291Y1061971I-938J-1425D01*
G03X846026Y1061992I-267J-1686D01*
G01X781299D01*
G03X778296Y1060747I1J-4247D01*
G01X181173Y463625D01*
Y463626D01*
G02X174594Y460900I-6581J6580D01*
G01X53223D01*
G03X50519Y459780I0J-3824D01*
G01X41069Y450330D01*
Y450331D01*
G02X35924Y448199I-5147J5146D01*
G01X22372D01*
G03X21424Y447933I0J-1823D01*
G03X21083Y447665I948J-1557D01*
G01X20583Y447165D01*
G02X19827Y446852I-756J756D01*
G01X11075D01*
X11069Y446846D01*
G01Y462594D02*
X19394D01*
X19400Y462600D01*
G03X19908Y462811I-1J719D01*
G01X20634Y463536D01*
G02X21513Y463900I879J-879D01*
G01X23799D01*
G02X26248Y462885I-1J-3464D01*
G01X26486Y462648D01*
G01X11069Y466531D02*
X19094D01*
X19100Y466537D01*
G02X20022Y466155I0J-1304D01*
G01X20511Y465666D01*
G03X21636Y465200I1125J1125D01*
G01X23800D01*
G02X25806Y464757I0J-4764D01*
G03X26499Y465200I205J443D01*
G01Y466250D01*
G01X11069Y494090D02*
X19640D01*
X19646Y494096D01*
G03X20711Y494537I0J1506D01*
G01X20861Y494687D01*
G02X22573Y495396I1712J-1712D01*
G01X39269D01*
G03X43571Y497178I0J6084D01*
G01X75021Y528627D01*
X75106Y528722D01*
X835640Y1456108D01*
X835635Y1456113D01*
X846135Y1466613D01*
G02X846751Y1467014I1255J-1255D01*
G02X848686Y1466605I653J-1691D01*
G01X848888Y1466402D01*
G01X11069Y478342D02*
X19194D01*
X19200Y478348D01*
G03X19991Y478675I1J1118D01*
G01X20503Y479188D01*
G02X21614Y479648I1111J-1111D01*
G01X23699D01*
G02X26014Y478689I0J-3274D01*
G01X26299Y478404D01*
G01X11069Y482279D02*
X19394D01*
X19400Y482285D01*
G02X19800Y482120I1J-565D01*
G01X20486Y481433D01*
G03X21657Y480948I1171J1171D01*
G01X23699D01*
G02X25744Y480467I3J-4575D01*
G03X26515Y480944I238J477D01*
G01Y481798D01*
G01X11069Y513775D02*
X18994D01*
X19000Y513781D01*
G02X20330Y513230I0J-1881D01*
G01X20906Y512654D01*
G03X21616Y512360I710J710D01*
G01X24135D01*
G03X24922Y512686I0J1113D01*
G03X25329Y512995I-923J1639D01*
G01X26441Y514107D01*
G03X27199Y515937I-1830J1830D01*
G01Y519980D01*
G02X27740Y521811I3366J1D01*
G01X27754Y521832D01*
G02X28031Y522175I1761J-1139D01*
G01X192400Y764246D01*
X817275Y1826081D01*
X843620Y1870848D01*
X843997Y1871486D01*
X844236Y1871893D01*
G02X846259Y1873050I2024J-1191D01*
G01X849999D01*
G02X852536Y1871999I0J-3588D01*
G01X853499Y1871036D01*
G01X850099Y1871056D02*
G03X849603Y1871721I-694J0D01*
G03X849405Y1871750I-199J-665D01*
G01X846260D01*
G03X845357Y1871233I0J-1048D01*
G01X844804Y1870294D01*
X818397Y1825421D01*
X193499Y763550D01*
X29104Y521441D01*
G03X28499Y519980I1460J-1460D01*
G01Y515938D01*
G02X27360Y513188I-3888J-1D01*
G01Y513187D01*
X26861Y512688D01*
X26602Y512430D01*
G02X26058Y511968I-3104J3103D01*
G02X23866Y511060I-2192J2192D01*
G01X22170D01*
G03X21453Y510763I0J-1014D01*
G01X21222Y510531D01*
X20942Y510251D01*
G02X19959Y509844I-983J983D01*
G01X11075D01*
X11069Y509838D01*
G01Y498027D02*
X19554D01*
X19560Y498033D01*
G02X20707Y497558I0J-1622D01*
G03X22788Y496696I2081J2081D01*
G01X39693D01*
G03X42351Y497797I0J3759D01*
G01X74101Y529547D01*
X834716Y1457033D01*
X845209Y1467526D01*
G02X846284Y1468224I2187J-2192D01*
G02X851521Y1467113I1764J-4584D01*
G01X852288Y1466346D01*
G01X11069Y525586D02*
X19553D01*
X19559Y525592D01*
G03X20771Y526094I0J1714D01*
G02X22699Y526892I1927J-1928D01*
G01X24399D01*
G02X26031Y526216I0J-2308D01*
G01X26599Y525648D01*
G01X11069Y529523D02*
X19294D01*
X19300Y529529D01*
G02X20275Y529125I0J-1379D01*
G01X20648Y528751D01*
G03X21999Y528192I1350J1351D01*
G01X25099D01*
G03X25765Y528468I0J942D01*
G01X26599Y529302D01*
G01X27199Y539600D02*
X25002Y537403D01*
X11075D01*
X11069Y537397D01*
G01X33799Y553050D02*
X33698Y553151D01*
X11075D01*
X11069Y553145D01*
G01X42867Y548450D02*
X36567Y542150D01*
X22399D01*
X21589Y541340D01*
X11075D01*
X11069Y541334D01*
G01X33307Y557938D02*
X31757D01*
X30745Y558950D01*
X27900D01*
X26038Y557088D01*
X11075D01*
X11069Y557082D01*
G01X26199Y547176D02*
X26023Y547000D01*
X24549D01*
X22335Y549214D01*
X11075D01*
X11069Y549208D01*
G01X49799Y559150D02*
X35926Y545277D01*
X11075D01*
X11069Y545271D01*
G01Y580704D02*
X18349D01*
X18355Y580710D01*
G03X20472Y581587I0J2994D01*
G02X21493Y582010I1021J-1021D01*
G01X28861D01*
G03X32168Y583380I0J4677D01*
G01X83492Y634704D01*
G03X85499Y639550I-4847J4846D01*
G01Y641514D01*
G02X87999Y647550I8536J0D01*
G01X147999Y707550D01*
G03X152551Y718540I-10990J10990D01*
G01Y763390D01*
G02X153637Y766011I3708J-1D01*
G01X193787Y806161D01*
G03X196099Y811743I-5581J5581D01*
G01Y1177535D01*
G03X194659Y1181011I-4916J0D01*
G01X174209Y1201461D01*
G02X172499Y1205589I4128J4128D01*
G01Y1384722D01*
G02X173386Y1386863I3028J0D01*
G01X173886Y1387363D01*
G03X175172Y1390468I-3107J3106D01*
G01Y1433294D01*
G03X173699Y1436850I-5029J0D01*
G01X143994Y1466555D01*
G03X139499Y1468417I-4495J-4495D01*
G01X126279D01*
G02X124290Y1469241I0J2813D01*
G01X31549Y566050D02*
X29249Y563750D01*
X22253D01*
X21041Y564962D01*
X11075D01*
X11069Y564956D01*
G01X42599Y567850D02*
X39099Y564350D01*
X33299D01*
X29499Y560550D01*
X21375D01*
X20900Y561025D01*
X11075D01*
X11069Y561019D01*
G01X25581Y567763D02*
X24445Y568899D01*
X11075D01*
X11069Y568893D01*
G01X27699Y573750D02*
X26785Y572836D01*
X11075D01*
X11069Y572830D01*
G01Y584641D02*
X18459D01*
X18465Y584647D01*
G02X20474Y583815I0J-2841D01*
G03X21693Y583310I1219J1219D01*
G01X28860D01*
G03X31249Y584300I0J3377D01*
G01X36998Y590049D01*
Y590050D01*
X82572Y635624D01*
G03X84199Y639551I-3926J3927D01*
G01Y641514D01*
G02X87080Y648470I9836J1D01*
G01X87079D01*
X147079Y708470D01*
G03X151250Y718540I-10070J10070D01*
G01X151251Y718539D01*
Y763389D01*
G02X152718Y766931I5008J1D01*
G01X192868Y807081D01*
G03X194799Y811743I-4662J4662D01*
G01Y1177534D01*
G03X193739Y1180092I-3616J0D01*
G01X173289Y1200542D01*
G02X171199Y1205588I5048J5047D01*
G01Y1384723D01*
G02X172466Y1387782I4328J-1D01*
G01X172966Y1388282D01*
G03X173872Y1390469I-2187J2187D01*
G01Y1423987D01*
G03X173636Y1424223I-236J0D01*
G02X173400Y1424459I0J236D01*
G01Y1426387D01*
G02X173636Y1426623I236J0D01*
G03X173872Y1426859I0J236D01*
G01Y1433250D01*
G03X172748Y1435961I-3834J-1D01*
G01X143074Y1465635D01*
G03X139498Y1467117I-3576J-3574D01*
G01X124999D01*
G03X123808Y1465926I0J-1191D01*
G01Y1465050D01*
G01X28808Y593150D02*
X28179Y592521D01*
X11075D01*
X11069Y592515D01*
G01X28700Y596549D02*
X28609Y596458D01*
X11075D01*
X11069Y596452D01*
G01X32200Y603710D02*
X30810D01*
X27495Y600395D01*
X11075D01*
X11069Y600389D01*
G01Y616137D02*
X18274D01*
X18280Y616143D01*
G02X20484Y615230I0J-3117D01*
G03X21508Y614806I1024J1024D01*
G01X50213D01*
G03X60803Y619194I-2J14978D01*
G01X61078Y619469D01*
X61079D01*
X66872Y625262D01*
G03X70698Y634500I-9239J9238D01*
G01X70699Y634499D01*
Y666977D01*
G02X71980Y670070I4373J1D01*
G01X141679Y739769D01*
G03X143684Y744609I-4840J4840D01*
G01Y766031D01*
G02X145334Y770015I5633J1D01*
G01X185434Y810115D01*
G03X187399Y814859I-4744J4744D01*
G01Y1174418D01*
X187398D01*
G03X186306Y1177057I-3733J1D01*
G01X165305Y1198058D01*
G02X163799Y1201694I3638J3637D01*
G01Y1375878D01*
X163798D01*
G03X163046Y1377696I-2572J1D01*
G01X135046Y1405696D01*
G02X132449Y1411966I6269J6269D01*
G01Y1447980D01*
G03X130100Y1453651I-8020J0D01*
G01X118249Y1465502D01*
G02X115899Y1471176I5676J5675D01*
G01Y1647522D01*
G02X118397Y1653553I8528J1D01*
G01X149796Y1684952D01*
G03X153249Y1693288I-8336J8336D01*
G01Y1752099D01*
G03X152924Y1752424I-325J0D01*
G02X152599Y1752749I0J325D01*
G01Y1754499D01*
G02X152924Y1754824I325J0D01*
G03X153249Y1755149I0J325D01*
G01Y1756899D01*
G03X152924Y1757224I-325J0D01*
G02X152599Y1757549I0J325D01*
G01Y1759299D01*
G02X152924Y1759624I325J0D01*
G03X153249Y1759949I0J325D01*
G01Y1761699D01*
G03X152924Y1762024I-325J0D01*
G02X152599Y1762349I0J325D01*
G01Y1764099D01*
G02X152924Y1764424I325J0D01*
G03X153249Y1764749I0J325D01*
G01Y1766499D01*
G03X152924Y1766824I-325J0D01*
G02X152599Y1767149I0J325D01*
G01Y1768899D01*
G02X152924Y1769224I325J0D01*
G03X153249Y1769549I0J325D01*
G01Y1801600D01*
X153250D01*
G03X151941Y1804759I-4469J-1D01*
G01X151584Y1805115D01*
X149006Y1807692D01*
X149007Y1807693D01*
G02X147600Y1811090I3396J3396D01*
G01Y1863700D01*
X147601D01*
G03X145478Y1868819I-7241J-3D01*
G01X144248Y1870049D01*
Y1870051D01*
X143863Y1870436D01*
G03X139605Y1872200I-4258J-4256D01*
G01X124734D01*
G03X123393Y1870859I0J-1341D01*
G01X11069Y612200D02*
X18295D01*
X18301Y612206D01*
G03X20537Y613132I0J3162D01*
G02X21440Y613506I903J-903D01*
G01X50212D01*
G03X61723Y618274I0J16279D01*
G01X67792Y624342D01*
G03X71999Y634500I-10158J10157D01*
G01Y666977D01*
G02X72899Y669150I3073J0D01*
G01X142599Y738850D01*
G03X144984Y744608I-5760J5759D01*
G01Y766031D01*
G02X146253Y769095I4333J0D01*
G01X186353Y809195D01*
G03X188699Y814859I-5663J5663D01*
G01Y1174418D01*
G03X187225Y1177977I-5033J0D01*
G01X166225Y1198977D01*
G02X165099Y1201695I2718J2718D01*
G01Y1375878D01*
G03X163965Y1378616I-3872J0D01*
G01X135965Y1406616D01*
G02X133749Y1411966I5350J5350D01*
G01Y1447980D01*
G03X131019Y1454571I-9320J0D01*
G01X119169Y1466421D01*
G02X117199Y1471177I4756J4756D01*
G01Y1647522D01*
G02X119316Y1652633I7228J0D01*
G01X150716Y1684033D01*
G03X154549Y1693287I-9256J9255D01*
G01Y1801600D01*
G03X152860Y1805679I-5768J1D01*
G01X152503Y1806035D01*
X149926Y1808612D01*
G02X148900Y1811089I2477J2477D01*
G01Y1863700D01*
G03X146398Y1869739I-8541J-1D01*
G01X146250Y1869888D01*
X144782Y1871356D01*
G03X139606Y1873500I-5176J-5176D01*
G01X125412D01*
G02X123592Y1874254I0J2574D01*
G01X31598Y607102D02*
X31002D01*
X28232Y604332D01*
X11075D01*
X11069Y604326D01*
G01Y631885D02*
X19632D01*
X19638Y631891D01*
G02X20596Y631494I0J-1355D01*
G03X22867Y630554I2270J2271D01*
G01X54748D01*
G03X60579Y632970I0J8245D01*
G03X62199Y636879I-3907J3910D01*
G01Y668554D01*
G02X64482Y674066I7794J1D01*
G01X64481Y674067D01*
X134581Y744167D01*
X134582D01*
G03X135714Y746900I-2733J2733D01*
G01Y768692D01*
G02X137249Y772398I5243J-1D01*
G01X178200Y813349D01*
G03X179699Y816968I-3619J3619D01*
G01Y1171886D01*
X179698Y1171885D01*
G03X178772Y1174123I-3166J1D01*
G01X158221Y1194674D01*
G02X156399Y1199073I4401J4400D01*
G01Y1373115D01*
G03X155861Y1374413I-1834J0D01*
G01X127120Y1403154D01*
G02X125049Y1408154I5002J5001D01*
G01Y1446349D01*
G03X123716Y1449567I-4552J0D01*
G01X110615Y1462668D01*
G02X108499Y1467777I5111J5110D01*
G01Y1684580D01*
G03X107541Y1686893I-3271J0D01*
G01X102641Y1691793D01*
G02X100949Y1695878I4087J4086D01*
G01Y1737453D01*
G02X102221Y1740524I4343J0D01*
G02X105883Y1741850I3663J-4396D01*
G03X105973I45J4626D01*
G03X109154Y1743205I-91J4625D01*
G01X109499Y1743550D01*
G01X11069Y627948D02*
X19683D01*
X19689Y627954D01*
G03X20737Y628388I0J1482D01*
G02X22828Y629254I2091J-2091D01*
G01X54749D01*
G03X61499Y632050I0J9546D01*
G03X63499Y636878I-4828J4828D01*
G01Y668555D01*
G02X65401Y673147I6494J0D01*
G01X135501Y743247D01*
Y743248D01*
G03X137014Y746901I-3652J3652D01*
G01Y768691D01*
G02X138169Y771479I3943J0D01*
G01X179119Y812429D01*
G03X180999Y816968I-4538J4538D01*
G01Y1171885D01*
G03X179691Y1175043I-4466J0D01*
G01X159141Y1195593D01*
G02X157699Y1199074I3481J3481D01*
G01Y1373116D01*
G03X156781Y1375332I-3134J0D01*
G01X128040Y1404073D01*
G02X126349Y1408155I4082J4082D01*
G01Y1446349D01*
G03X124635Y1450487I-5852J0D01*
G01X111535Y1463587D01*
G02X109799Y1467778I4191J4191D01*
G01Y1684580D01*
G03X108460Y1687813I-4571J1D01*
G01X103561Y1692712D01*
G02X102249Y1695879I3167J3167D01*
G01Y1737812D01*
G02X102924Y1739442I2305J0D01*
G02X105599Y1740550I2675J-2675D01*
G01X105999D01*
G03X107782Y1740861I-115J5925D01*
G02X109399Y1739701I392J-1160D01*
G01Y1739550D01*
G01X11069Y643696D02*
X18472D01*
X18478Y643702D01*
G03X20651Y644602I0J3073D01*
G02X21617Y645002I966J-966D01*
G01X50499D01*
G03X55498Y650001I0J4999D01*
G01Y653793D01*
X55499D01*
Y674795D01*
G02X58649Y682400I10755J0D01*
G01X118248Y741999D01*
G03X121199Y749124I-7124J7124D01*
G01Y1032799D01*
G03X118839Y1038501I-8063J2D01*
G01X118470Y1038870D01*
X118469Y1038869D01*
X101049Y1056290D01*
G02X98779Y1061770I5480J5480D01*
G01Y1329741D01*
G02X99549Y1331600I2629J0D01*
G01X101799Y1333850D01*
G02X103489Y1334550I1690J-1690D01*
G01X106799D01*
G02X108838Y1333706I1J-2883D01*
G01X109228Y1333315D01*
G01X11069Y647633D02*
X19613D01*
X19619Y647639D01*
G02X20640Y647216I0J-1444D01*
G02X21121Y646834I-1418J-2279D01*
G03X22867Y646302I1747J2602D01*
G01X50499D01*
G03X54198Y650001I0J3699D01*
G01Y653793D01*
X54199Y653792D01*
Y674794D01*
G02X57730Y683319I12055J1D01*
G01X57729D01*
X117329Y742919D01*
G03X119899Y749124I-6205J6205D01*
G01Y1032800D01*
G03X117919Y1037581I-6762J0D01*
G01X100129Y1055370D01*
X100130Y1055371D01*
G02X97479Y1061769I6399J6400D01*
G01Y1329741D01*
G02X98630Y1332520I3929J1D01*
G01X100679Y1334569D01*
G02X103772Y1335850I3093J-3093D01*
G01X106799D01*
G03X108828Y1336691I-1J2870D01*
G01X109228Y1337090D01*
G01X11069Y663381D02*
X11075Y663387D01*
X19862D01*
G02X21339Y662775I0J-2089D01*
G01X21701Y662412D01*
G03X22577Y662050I875J876D01*
G01X40199D01*
G03X44699Y666550I0J4500D01*
G01Y678455D01*
G02X48330Y687219I12396J-2D01*
G01X48329Y687220D01*
X102941Y741832D01*
G03X104848Y746436I-4604J4604D01*
G01Y751789D01*
X104849Y751790D01*
Y928305D01*
G02X105579Y930070I2496J1D01*
G02X106983Y930650I1402J-1404D01*
G01X107399D01*
G03X108149Y930960I1J1060D01*
G01X108845Y931657D01*
G01X11069Y659444D02*
X19162D01*
X19168Y659450D01*
G03X21099Y660250I0J2731D01*
G02X22306Y660750I1207J-1207D01*
G01X40199D01*
G03X45999Y666550I0J5800D01*
G01Y678454D01*
G02X49249Y686300I11096J0D01*
G01X103861Y740912D01*
X103860Y740913D01*
G03X106148Y746437I-5523J5523D01*
G01Y751250D01*
X106149Y751251D01*
Y913844D01*
G02X106374Y914069I225J0D01*
G01X106375D01*
G03X106600Y914294I0J225D01*
G01Y916244D01*
G03X106375Y916469I-225J0D01*
G01X106374D01*
G02X106149Y916694I0J225D01*
G01Y928305D01*
G02X106499Y929150I1195J0D01*
G02X106982Y929350I483J-483D01*
G01X107399D01*
G02X108424Y928926I1J-1449D01*
G01X109099Y928250D01*
G01X11069Y675192D02*
X18982D01*
X18988Y675198D01*
G03X20200Y675700I0J1714D01*
G01X20650Y676151D01*
G02X21533Y676516I883J-886D01*
G03X21536Y676517I-842J2531D01*
G01X26438D01*
G03X31419Y678581I-2J7046D01*
G01Y678580D01*
X32919Y680080D01*
X32920D01*
X33347Y680507D01*
G03X35000Y684499I-3994J3992D01*
G01Y691379D01*
G02X36500Y695000I5121J0D01*
G01X94249Y752749D01*
Y752750D01*
G03X96100Y757219I-4468J4468D01*
G01Y836499D01*
G03X93811Y842029I-7819J2D01*
G01X93170Y842670D01*
X93169Y842669D01*
X62736Y873102D01*
G02X60500Y878500I5398J5398D01*
G01Y1325111D01*
G02X63250Y1331750I9389J0D01*
G01X84500Y1353000D01*
G02X89328Y1355000I4828J-4828D01*
G01X94486D01*
G02X96216Y1354283I0J-2445D01*
G01X96294Y1354206D01*
G02X97000Y1352500I-1706J-1705D01*
G01Y1349190D01*
G03X98080Y1346580I3691J-1D01*
G03X100821Y1345675I2269J2268D01*
G02X101350Y1345500I91J-612D01*
G01X102350Y1344500D01*
G01X11069Y679129D02*
X18347D01*
X18353Y679135D01*
G02X20569Y678217I0J-3134D01*
G03X21535Y677817I966J966D01*
G01X26437D01*
G03X30500Y679500I0J5746D01*
G01X32427Y681427D01*
G03X33700Y684500I-3073J3073D01*
G01Y691380D01*
G02X35581Y695919I6421J-2D01*
G01X35580D01*
X93330Y753669D01*
G03X94800Y757218I-3549J3549D01*
G01Y836500D01*
G03X92891Y841109I-6518J0D01*
G01X62060Y871940D01*
X62059Y871939D01*
X61816Y872182D01*
G02X59200Y878499I6319J6317D01*
G01Y1325112D01*
G02X62331Y1332669I10689J-1D01*
G01X62330D01*
X83580Y1353919D01*
X83581D01*
G02X89327Y1356300I5748J-5747D01*
G01X94494D01*
G02X97130Y1355208I0J-3728D01*
G01X97211Y1355129D01*
G02X98299Y1352500I-2624J-2626D01*
G01X98300D01*
Y1349190D01*
G03X99000Y1347500I2390J0D01*
G03X101696I1348J1348D01*
G01X102350Y1348154D01*
G01X27700Y682700D02*
X23391Y687009D01*
X11075D01*
X11069Y687003D01*
G01X44046Y799554D02*
Y795575D01*
X33915Y785444D01*
X11067D01*
X11060Y785451D01*
G01X35300Y789375D02*
X11073D01*
X11060Y789388D01*
G01Y781514D02*
X11073Y781501D01*
X33501D01*
X45100Y793100D01*
G01X37416Y799033D02*
X35632Y797249D01*
X11073D01*
X11060Y797262D01*
G01X37099Y811350D02*
X34809Y809060D01*
X11073D01*
X11060Y809073D01*
G01Y805136D02*
X11073Y805123D01*
X42123D01*
X43300Y806300D01*
G01X52299Y801450D02*
X40711D01*
X40511Y801250D01*
X11111D01*
X11060Y801199D01*
G01X35559Y795112D02*
X33759Y793312D01*
X11073D01*
X11060Y793325D01*
G01X31699Y814350D02*
X28599D01*
X27246Y812997D01*
X11073D01*
X11060Y813010D01*
G01Y832696D02*
X11073Y832683D01*
X20832D01*
X27599Y839450D01*
X30236D01*
X33436Y836250D01*
X44899D01*
G01X46700Y820100D02*
X45251Y818651D01*
X36898D01*
X34678Y820871D01*
X11073D01*
X11060Y820884D01*
G01Y816947D02*
X11073Y816934D01*
X49766D01*
X53950Y812750D01*
X59800D01*
G01X11060Y836633D02*
X11073Y836620D01*
X21669D01*
X26099Y841050D01*
X30899D01*
X33899Y838050D01*
X43729D01*
X44029Y838350D01*
X54499D01*
X54799Y838050D01*
G01X50399Y841450D02*
X49199Y842650D01*
X24999D01*
X22906Y840557D01*
X11073D01*
X11060Y840570D01*
G01Y844507D02*
X23478D01*
X25300Y846329D01*
X53320D01*
X55299Y844350D01*
G01X61600Y850531D02*
X22018D01*
X20181Y852368D01*
X11073D01*
X11060Y852381D01*
G01Y848444D02*
X11073Y848431D01*
X47200D01*
G01X23299Y863050D02*
Y858850D01*
X20754Y856305D01*
X11073D01*
X11060Y856318D01*
G01X11069Y1360230D02*
X19020D01*
X19026Y1360236D01*
G03X21187Y1361131I0J3056D01*
G02X22165Y1361536I978J-978D01*
G01X96745D01*
G02X98329Y1360880I0J-2240D01*
G01X98576Y1360633D01*
G03X101193Y1359550I2616J2617D01*
G01X110005D01*
G02X111702Y1358847I0J-2400D01*
G01X112291Y1358258D01*
G03X112440Y1358196I149J148D01*
G01X11069Y1364167D02*
X18899D01*
X18905Y1364173D01*
G02X20897Y1363348I0J-2817D01*
G03X22133Y1362836I1236J1236D01*
G01X93638D01*
X93644Y1362842D01*
X96384D01*
G02X99496Y1361553I0J-4401D01*
G03X101193Y1360850I1697J1697D01*
G01X111309D01*
G03X112999Y1361550I0J2390D01*
G01X11069Y1379915D02*
X11075Y1379921D01*
X19953D01*
G02X21143Y1379428I0J-1683D01*
G01X21277Y1379294D01*
G03X22699Y1378705I1422J1422D01*
G01X26610D01*
G03X28392Y1379443I0J2520D01*
G01X28796Y1379847D01*
G03X29499Y1381544I-1697J1697D01*
G01Y1389529D01*
G03X29379Y1390133I-1577J1D01*
G01X29153Y1390678D01*
G03X28596Y1391050I-557J-231D01*
G01X28499D01*
G01X11069Y1375978D02*
X18519D01*
X18525Y1375984D01*
G03X21099Y1377050I0J3640D01*
G02X21956Y1377405I857J-857D01*
G01X26610D01*
G03X29312Y1378523I1J3821D01*
G01X29716Y1378927D01*
G03X30799Y1381544I-2617J2616D01*
G01Y1388616D01*
G02X31566Y1389383I767J0D01*
G01X32333D01*
G01X32451Y1411468D02*
G03X31499Y1409170I2298J-2298D01*
G01Y1401947D01*
G02X29918Y1398130I-5398J0D01*
G01X26118Y1394330D01*
X25759Y1393970D01*
G02X23988Y1393237I-1770J1771D01*
G01X23201D01*
X23188Y1393224D01*
G03X21833Y1392547I340J-2375D01*
G01X21702Y1392416D01*
G02X20051Y1391732I-1651J1651D01*
G01X11075D01*
X11069Y1391726D01*
G01Y1395663D02*
X19574D01*
X19580Y1395669D01*
G02X20946Y1395103I0J-1932D01*
G03X22281Y1394550I1335J1335D01*
G01X23188D01*
X23201Y1394537D01*
X23988D01*
G03X24839Y1394889I0J1204D01*
G01X25197Y1395248D01*
X28998Y1399049D01*
X28999D01*
G03X30198Y1401947I-2899J2896D01*
G01X30199Y1401946D01*
Y1409050D01*
G03X29280Y1411269I-3138J0D01*
G01X28999Y1411550D01*
G01X11069Y1415350D02*
X19322D01*
X19328Y1415356D01*
G03X20996Y1416047I0J2359D01*
G02X22693Y1416750I1697J-1697D01*
G01X22999D01*
Y1416751D01*
G03X26753Y1418305I1J5309D01*
G01X27248Y1418799D01*
X30473Y1422023D01*
G03X32140Y1426050I-4027J4026D01*
G01Y1429778D01*
G02X33206Y1432352I3640J0D01*
G01X11069Y1419287D02*
X18858D01*
X18864Y1419293D01*
G02X20387Y1418662I0J-2154D01*
G03X21864Y1418050I1477J1476D01*
G01X22999D01*
G03X25834Y1419225I-1J4010D01*
G01X26329Y1419719D01*
X29553Y1422943D01*
G03X30840Y1426050I-3107J3107D01*
G01Y1433727D01*
G03X30499Y1434550I-1164J0D01*
G01X76000Y1431100D02*
X61558Y1416658D01*
X29040D01*
X26500Y1414118D01*
Y1412200D01*
X21781Y1407481D01*
X11075D01*
X11069Y1407475D01*
G01Y1446846D02*
X19128D01*
X19134Y1446852D01*
G03X20863Y1447568I0J2445D01*
G02X22273Y1448152I1410J-1410D01*
G01X23536D01*
G03X26210Y1449259I1J3781D01*
G01X26587Y1449637D01*
X30391Y1453441D01*
G03X32299Y1458050I-4610J4608D01*
G01Y1461567D01*
G02X32499Y1462050I683J0D01*
G01X32575Y1462126D01*
G02X33915Y1462681I1340J-1340D01*
G01X11069Y1431098D02*
X19467D01*
X19473Y1431104D01*
G03X21257Y1431843I0J2523D01*
G02X22954Y1432546I1697J-1697D01*
G01X25100D01*
G03X27500Y1434946I0J2400D01*
G01Y1436550D01*
G02X27507Y1436821I4831J11D01*
G01X27554Y1437697D01*
G02X28284Y1439334I2501J-134D01*
G01X30086Y1441136D01*
G03X31499Y1444550I-3415J3413D01*
G01Y1447012D01*
G02X32094Y1448448I2031J0D01*
G01X11069Y1435035D02*
X18940D01*
X18946Y1435041D01*
G02X20411Y1434434I0J-2072D01*
G03X21831Y1433846I1420J1421D01*
G01X25100D01*
G03X26200Y1434946I0J1100D01*
G01Y1436895D01*
G02X27752Y1440642I5299J0D01*
G01X29166Y1442056D01*
G03X30199Y1444550I-2494J2494D01*
G01Y1446050D01*
G03X29673Y1447320I-1796J0D01*
G01X28697Y1448296D01*
G01X11069Y1462594D02*
X18494D01*
X18500Y1462600D01*
G03X20721Y1463520I0J3141D01*
G02X21638Y1463900I917J-917D01*
G01X23999D01*
G03X26303Y1464855I-1J3259D01*
G01X26499Y1465050D01*
X31206Y1469757D01*
G03X33299Y1474811I-5055J5054D01*
G01Y1479050D01*
G02X34336Y1481555I3542J1D01*
G01X34465Y1481683D01*
G01X11069Y1466531D02*
X18502D01*
X18508Y1466537D01*
G02X20630Y1465658I0J-3001D01*
G03X21736Y1465200I1106J1106D01*
G01X23998D01*
G03X25383Y1465775I-1J1958D01*
G01X25384Y1465776D01*
X25580Y1465971D01*
X30286Y1470677D01*
G03X31999Y1474810I-4134J4135D01*
G01Y1479636D01*
G03X30999Y1482050I-3414J0D01*
G01X11069Y1450783D02*
X19209D01*
X19215Y1450789D01*
G02X20999Y1450050I0J-2523D01*
G03X22174Y1449469I1445J1443D01*
G03X22443Y1449452I263J2025D01*
G01X23536D01*
G03X25290Y1450178I0J2481D01*
G01X25667Y1450556D01*
X26329Y1451219D01*
X29471Y1454361D01*
G03X30999Y1458050I-3689J3689D01*
G01Y1461019D01*
G03X30977Y1461319I-2120J-5D01*
G03X30378Y1462518I-2099J-299D01*
G01X11069Y1478342D02*
X19186D01*
X19192Y1478348D01*
G03X20966Y1479083I0J2509D01*
G01X21111Y1479228D01*
G02X21633Y1479520I778J-778D01*
G02X21887Y1479550I255J-1066D01*
G01X24099D01*
Y1479551D01*
G03X26578Y1480578I3J3497D01*
G01X26632Y1480634D01*
X27723Y1481725D01*
G03X28453Y1483487I-1762J1762D01*
G01Y1483490D01*
G02X28932Y1484644I1633J-1D01*
G01X31667Y1487379D01*
G03X32799Y1490112I-2733J2733D01*
G01Y1494550D01*
G02X34001Y1497452I4104J0D01*
G01X34099Y1497550D01*
G01X11069Y1482279D02*
X19254D01*
X19260Y1482285D01*
G02X20974Y1481575I0J-2424D01*
G01X21499Y1481050D01*
G03X21982Y1480850I483J483D01*
G01X24099D01*
G03X25653Y1481493I1J2197D01*
G01X25704Y1481545D01*
X26804Y1482645D01*
G03X27154Y1483489I-845J845D01*
G01Y1483490D01*
G02X28012Y1485564I2933J1D01*
G01X28676Y1486228D01*
X30793Y1488344D01*
G03X31499Y1490050I-1706J1705D01*
G01Y1495136D01*
G03X30499Y1497550I-3414J0D01*
G01X11069Y1509838D02*
X19440D01*
X19446Y1509844D01*
G03X20689Y1510359I0J1758D01*
G02X22357Y1511050I1668J-1668D01*
G01X22999D01*
G03X26194Y1512377I2J4505D01*
G01X26221Y1512405D01*
X26432Y1512616D01*
X26659Y1512842D01*
G03X27780Y1515550I-2708J2707D01*
G01Y1518549D01*
G02X29395Y1522445I5509J-1D01*
G01X30441Y1523491D01*
G02X33483Y1524751I3042J-3042D01*
G01X35227D01*
Y1524750D01*
G02X39105Y1523144I0J-5484D01*
G01X39599Y1522651D01*
X47077Y1515173D01*
X47078Y1515171D01*
G02X49199Y1510052I-5115J-5118D01*
G02Y1510050I-7245J-1D01*
G01Y1491550D01*
G03X52408Y1483803I10956J0D01*
G01X52409Y1483802D01*
X52635Y1483575D01*
X55829Y1480380D01*
X98991Y1437218D01*
X99630Y1436578D01*
G03X104045Y1434750I4414J4415D01*
G01X107817D01*
G03X110687Y1435939I0J4059D01*
G03X111299Y1438188I-3826J2249D01*
G01Y1443050D01*
G03X110854Y1444124I-1519J0D01*
G01X110772Y1444206D01*
G03X108999Y1444940I-1773J-1773D01*
G01Y1444941D01*
X104999D01*
G01X11069Y1498027D02*
X19381D01*
X19387Y1498033D01*
G02X21270Y1497253I0J-2663D01*
G03X22967Y1496550I1697J1697D01*
G01X23031D01*
G03X24728Y1497253I0J2400D01*
G01X29920Y1502445D01*
G03X30999Y1505050I-2605J2605D01*
G01Y1509766D01*
G03X30115Y1511900I-3018J0D01*
G01X33512Y1512051D02*
G03X32299Y1509123I2928J-2928D01*
G01Y1505050D01*
G02X30838Y1501523I-4988J0D01*
G01X25648Y1496333D01*
G02X23031Y1495250I-2616J2617D01*
G01X22967D01*
G02X22916I-25J3700D01*
G01X22501D01*
G03X21049Y1494648I0J-2052D01*
G01X21000Y1494600D01*
G02X19783Y1494096I-1217J1217D01*
G01X11075D01*
X11069Y1494090D01*
G01Y1513775D02*
X19183D01*
X19189Y1513781D01*
G02X20985Y1513037I0J-2540D01*
G01X21255Y1512767D01*
G03X22262Y1512350I1007J1007D01*
G01X22999D01*
G03X25265Y1513288I1J3204D01*
G01X25292Y1513316D01*
X25740Y1513765D01*
G03X26480Y1515550I-1785J1786D01*
G01Y1518550D01*
G02X28475Y1523365I6810J-1D01*
G01X29508Y1524398D01*
G02X33499Y1526051I3991J-3991D01*
G01X35228D01*
G02X40024Y1524064I-1J-6785D01*
G01X40518Y1523571D01*
X48146Y1515944D01*
X48151Y1515934D01*
G02X50500Y1510053I-6191J-5883D01*
G01X50499D01*
Y1491550D01*
G03X53327Y1484721I9657J-1D01*
G01X53499Y1484550D01*
X99911Y1438138D01*
Y1438137D01*
X100550Y1437497D01*
G03X104044Y1436050I3494J3496D01*
G01X107816D01*
G03X109647Y1436746I-1J2758D01*
G03X109999Y1437596I-850J850D01*
G01Y1442927D01*
G03X109849Y1443289I-512J0D01*
G03X108999Y1443641I-850J-850D01*
G01X107934D01*
G03X107053Y1443439I-1J-2018D01*
G01X106750Y1443135D01*
G03X106507Y1442550I585J-586D01*
G01Y1442050D01*
G02X106088Y1441040I-1429J1D01*
G02X105108Y1440634I-980J980D01*
G01X104935D01*
G01X38500Y1534600D02*
X36500D01*
X33100Y1531200D01*
X25949D01*
X20341Y1525592D01*
X11075D01*
X11069Y1525586D01*
G01X70099Y1540550D02*
X63263D01*
X62363Y1539650D01*
X41394D01*
X39794Y1538050D01*
X27414D01*
X22432Y1533068D01*
Y1531383D01*
X20578Y1529529D01*
X11075D01*
X11069Y1529523D01*
G01X24199Y1523700D02*
X22154Y1521655D01*
X11075D01*
X11069Y1521649D01*
G01X34896Y1555730D02*
X32317Y1553151D01*
X11075D01*
X11069Y1553145D01*
G01X44697Y1546793D02*
Y1547148D01*
X46099Y1548550D01*
Y1551696D01*
X45045Y1552750D01*
X34180D01*
X30644Y1549214D01*
X11075D01*
X11069Y1549208D01*
G01X41325Y1548747D02*
Y1548676D01*
X39949Y1547300D01*
X28349D01*
X26161Y1545112D01*
X24501D01*
X24336Y1545277D01*
X11075D01*
X11069Y1545271D01*
G01X91399Y1549550D02*
X91199Y1549350D01*
X64199D01*
X59299Y1544450D01*
X39405D01*
X38405Y1543450D01*
X25099D01*
X22989Y1541340D01*
X11075D01*
X11069Y1541334D01*
G01X81999Y1541550D02*
X80849Y1542700D01*
X78254D01*
X77804Y1543150D01*
X63599D01*
X61699Y1541250D01*
X40731D01*
X39131Y1539650D01*
X26750D01*
X20566Y1533466D01*
X11075D01*
X11069Y1533460D01*
G01X72599Y1546650D02*
X63899D01*
X60099Y1542850D01*
X40068D01*
X39068Y1541850D01*
X26299D01*
X21852Y1537403D01*
X11075D01*
X11069Y1537397D01*
G01X36340Y1558809D02*
X30858D01*
X29137Y1557088D01*
X11075D01*
X11069Y1557082D01*
G01Y1564956D02*
X18511D01*
X18517Y1564962D01*
G03X20559Y1565808I0J2888D01*
G01X20666Y1565915D01*
G02X21477Y1566251I811J-811D01*
G02X21655Y1566262I184J-1539D01*
G01X24999D01*
G03X27129Y1566818I0J4360D01*
G03X27499Y1567050I-2128J3805D01*
G03X29669Y1569455I-4131J5909D01*
G03X30520Y1572049I-6301J3504D01*
G01X11069Y1568893D02*
X18103D01*
X18109Y1568899D01*
G02X20265Y1568006I0J-3049D01*
G01X20266D01*
G03X21322Y1567568I1057J1056D01*
G01X24999D01*
G03X26573Y1567937I-1J3544D01*
G03X26856Y1568094I-1576J3174D01*
G03X28012Y1569771I-1325J2150D01*
G03X27123Y1572205I-2481J473D01*
G01X78462Y1574918D02*
X76607Y1576773D01*
X11075D01*
X11069Y1576767D01*
G01X60700Y1578962D02*
X22538D01*
X20790Y1580710D01*
X11075D01*
X11069Y1580704D01*
G01X37173Y1583074D02*
X35600Y1584647D01*
X11075D01*
X11069Y1584641D01*
G01X40200Y1586800D02*
X38416Y1588584D01*
X11075D01*
X11069Y1588578D01*
G01Y1616137D02*
X18513D01*
X18519Y1616143D01*
G02X20617Y1615274I0J-2967D01*
G03X21747Y1614806I1130J1130D01*
G01X23880D01*
G03X23958Y1614807I7J2501D01*
G03X25648Y1615538I-78J2500D01*
G01X28596Y1618486D01*
G03X30199Y1622356I-3870J3870D01*
G01Y1628360D01*
G03X29499Y1630050I-2390J0D01*
G01X11069Y1600389D02*
X17988D01*
X17994Y1600395D01*
G02X20654Y1599293I0J-3762D01*
G01X20655D01*
G03X21723Y1598850I1069J1068D01*
G01X22999D01*
G03X27779Y1600830I0J6760D01*
G01X29499Y1602550D01*
G03X30079Y1603950I-1400J1400D01*
G01Y1611550D01*
G03X29518Y1612906I-1917J1D01*
G01X28899Y1613524D01*
G01X11069Y1596452D02*
X18857D01*
X18863Y1596458D01*
G03X20944Y1597320I0J2943D01*
G02X21499Y1597550I555J-555D01*
G01X22999D01*
G03X24830Y1597760I3J8061D01*
G03X28699Y1599910I-1830J7850D01*
G01X30419Y1601630D01*
G03X31379Y1603949I-2320J2319D01*
G01Y1611568D01*
G02X32111Y1613336I2501J0D01*
G01X32299Y1613524D01*
G01X11069Y1612200D02*
X18566D01*
X18572Y1612206D01*
G03X20624Y1613056I0J2902D01*
G01X20625D01*
G02X21710Y1613506I1086J-1085D01*
G01X23879D01*
G03X23997Y1613507I27J3801D01*
G03X26568Y1614618I-117J3800D01*
G01X26999Y1615049D01*
Y1615050D01*
X29315Y1617366D01*
X29378Y1617428D01*
G03X31499Y1622550I-5122J5121D01*
G01Y1626050D01*
G02X31698Y1626994I2335J1D01*
G02X32183Y1627701I2135J-945D01*
G01X32663Y1628181D01*
G01X11069Y1631885D02*
X19367D01*
X19373Y1631891D01*
G02X20800Y1631300I0J-2018D01*
G01X21086Y1631014D01*
G03X22160Y1630569I1074J1074D01*
G01X23821D01*
G03X25482Y1631373I-324J2786D01*
G01X25829Y1631719D01*
X29079Y1634969D01*
X29108Y1634997D01*
G03X30554Y1638044I-3553J3553D01*
G03X30578Y1638519I-4697J475D01*
G01Y1638550D01*
X30579Y1638549D01*
Y1642701D01*
G03X29626Y1645002I-3254J0D01*
G01X11069Y1627948D02*
X18998D01*
X19004Y1627954D01*
G03X20539Y1628590I0J2171D01*
G02X22092Y1629273I1655J-1656D01*
G01X22174Y1629277D01*
G02X22200Y1629278I103J-2345D01*
G01X23972D01*
G03X26401Y1630453I-474J4078D01*
G01X26748Y1630799D01*
X29999Y1634050D01*
X30026Y1634078D01*
G03X31879Y1638550I-4471J4472D01*
G01Y1642282D01*
G02X33026Y1645051I3916J0D01*
G01X11069Y1643696D02*
X18566D01*
X18572Y1643702D01*
G03X20626Y1644553I0J2905D01*
G02X21710Y1645002I1084J-1084D01*
G01X23999D01*
G03X27101Y1646287I0J4387D01*
G01X28500Y1647686D01*
Y1647687D01*
X28620Y1647807D01*
X29181Y1648367D01*
Y1648368D01*
X29431Y1648618D01*
G03X30999Y1652405I-3789J3787D01*
G01Y1658713D01*
G02X31999Y1661127I3414J0D01*
G01X11069Y1647633D02*
X18407D01*
X18413Y1647639D01*
G02X20740Y1646675I0J-3291D01*
G03X21641Y1646302I901J901D01*
G01X23999D01*
G03X25465Y1646674I-3J3086D01*
G01Y1646673D01*
G03X26181Y1647207I-1468J2715D01*
G01X27011Y1648037D01*
X27200Y1648225D01*
Y1648227D01*
X28511Y1649538D01*
G03X29699Y1652406I-2868J2868D01*
G01Y1658386D01*
G03X28600Y1661039I-3752J0D01*
G01X11069Y1659444D02*
X19044D01*
X19050Y1659450D01*
G03X21353Y1660404I0J3257D01*
G02X22188Y1660750I835J-835D01*
G01X22500D01*
Y1660751D01*
G03X26410Y1662369I3J5525D01*
G01X26523Y1662484D01*
X30819Y1666780D01*
G03X31200Y1667700I-920J920D01*
G01Y1667702D01*
G02X31703Y1668916I1717J0D01*
G01X32494Y1669706D01*
G01X32700Y1673300D02*
X26000D01*
X23961Y1671261D01*
X11075D01*
X11069Y1671255D01*
G01Y1663381D02*
X18532D01*
X18538Y1663387D01*
G02X20590Y1662537I0J-2902D01*
G03X21766Y1662050I1176J1176D01*
G01X22500D01*
G03X25488Y1663287I1J4225D01*
G01X29300Y1667099D01*
X29546Y1667344D01*
G03X29876Y1667963I-857J854D01*
G03Y1667965I-1210J1D01*
G03X29896Y1668103I-1185J242D01*
G03X29900Y1668200I-1206J98D01*
G03X29546Y1669053I-1207J-1D01*
G01X29100Y1669500D01*
G01X39324Y1780623D02*
X30499D01*
X25684Y1785438D01*
X11073D01*
X11060Y1785451D01*
G01X43751Y1780559D02*
X43642Y1780450D01*
X41698D01*
X40072Y1778823D01*
X29499D01*
X26821Y1781501D01*
X11073D01*
X11060Y1781514D01*
G01X47440Y1761391D02*
X43078Y1765753D01*
X11073D01*
X11060Y1765766D01*
G01X47604Y1769005D02*
X47199D01*
X46514Y1769690D01*
X11073D01*
X11060Y1769703D01*
G01X45782Y1771877D02*
X44032Y1773627D01*
X11073D01*
X11060Y1773640D01*
G01X47499Y1775350D02*
X46399Y1776450D01*
X28999D01*
X27885Y1777564D01*
X11073D01*
X11060Y1777577D01*
G01X30274Y1787238D02*
X24200Y1793312D01*
X11073D01*
X11060Y1793325D01*
G01X38878Y1799571D02*
X37263Y1801186D01*
X11073D01*
X11060Y1801199D01*
G01X34599Y1805123D02*
X11073D01*
X11060Y1805136D01*
G01X35675Y1783450D02*
X35673Y1783452D01*
X30499D01*
X24576Y1789375D01*
X11073D01*
X11060Y1789388D01*
G01X32099Y1797150D02*
X32000Y1797249D01*
X11073D01*
X11060Y1797262D01*
G01X28550Y1828153D02*
X27957Y1828746D01*
X11073D01*
X11060Y1828759D01*
G01X29899Y1821050D02*
X25784Y1816935D01*
X11073D01*
X11060Y1816948D01*
G01X34099Y1822850D02*
X28499D01*
X26521Y1820872D01*
X11073D01*
X11060Y1820885D01*
G01X26099Y1824950D02*
X25958Y1824809D01*
X11073D01*
X11060Y1824822D01*
G01X25999Y1842550D02*
X24006Y1840557D01*
X11073D01*
X11060Y1840570D01*
G01X43099Y1833850D02*
X38540Y1838409D01*
X21353D01*
X19577Y1836633D01*
X11060D01*
G01X39699Y1833850D02*
X12240D01*
X11073Y1832683D01*
X11060Y1832696D01*
G01X26299Y383854D02*
X26926Y384481D01*
G02X28399Y385091I1473J-1473D01*
G01X30299D01*
G02X31015Y384795I1J-1012D01*
G01X31479Y384330D01*
X62322Y353488D01*
G02X63699Y350166I-3322J-3323D01*
G01Y227334D01*
G03X65456Y223093I5999J1D01*
G01X92007Y196542D01*
G02X99999Y177250I-19292J-19293D01*
G01Y134995D01*
X99998Y134996D01*
G02X98579Y131570I-4845J0D01*
G02X92014Y128850I-6565J6563D01*
G01X87016D01*
G02X86099Y129767I0J917D01*
G02X86899Y130567I800J0D01*
G01X26299Y387629D02*
X26857Y387071D01*
G03X28499Y386391I1642J1642D01*
G01X30299D01*
G02X31935Y385714I1J-2313D01*
G01X31948Y385700D01*
X63242Y354408D01*
G02X64999Y350166I-4242J-4242D01*
G01Y227335D01*
G03X66376Y224013I4699J1D01*
G01X92927Y197462D01*
G02X101299Y177250I-20212J-20212D01*
G01Y134996D01*
G02X99499Y130650I-6146J0D01*
G02X92015Y127550I-7484J7484D01*
G01X88423D01*
G03X88146Y127534I4J-2472D01*
G03X87835Y127478I284J-2469D01*
G03X86671Y126822I593J-2413D01*
G01X86599Y126750D01*
G01X26299Y399601D02*
G02X27536Y400838I1237J0D01*
G01X30862D01*
G02X31799Y400450I0J-1325D01*
G01X69342Y362907D01*
G02X71099Y358665I-4242J-4242D01*
G01Y294350D01*
G03X72470Y291040I4681J0D01*
G01X125479Y238031D01*
X126008Y237501D01*
G03X130599Y235600I4590J4591D01*
G01X816263D01*
G03X821425Y237737I1J7300D01*
G01X836553Y252863D01*
G02X839875Y254240I3323J-3322D01*
G01X859116D01*
G02X860299Y253750I0J-1673D01*
G01X871899Y242150D01*
G03X874555Y241050I2656J2656D01*
G01X876199D01*
G02X876593Y241015I-1J-2250D01*
G02X877571Y240610I0J-1383D01*
G01X878078Y240103D01*
G01X26299Y403376D02*
X27162Y402513D01*
G03X28067Y402138I905J905D01*
G01X30418D01*
G02X33035Y401054I0J-3701D01*
G01X70262Y363827D01*
G02X72399Y358665I-5163J-5161D01*
G01Y294223D01*
G03X73299Y292050I3073J0D01*
G01X126249Y239100D01*
X126928Y238420D01*
G03X130599Y236900I3670J3671D01*
G01X816263D01*
G03X820505Y238657I0J5999D01*
G01X835633Y253783D01*
G02X839875Y255540I4242J-4242D01*
G01X859118D01*
G02X861218Y254670I0J-2970D01*
G01X873018Y242870D01*
G03X874273Y242350I1255J1255D01*
G01X875999D01*
G03X876939Y242740I-1J1330D01*
G01X878078Y243878D01*
G01X26524Y426720D02*
X26598Y426647D01*
G03X28499Y425859I1902J1901D01*
G01X29699D01*
G02X32653Y424636I1J-4177D01*
G01X32718Y424570D01*
X78068Y379220D01*
G02X79799Y375041I-4179J-4179D01*
G01Y373117D01*
G03X80049Y372867I250J0D01*
G01X80050D01*
G02X80300Y372617I0J-250D01*
G01Y370717D01*
G02X80050Y370467I-250J0D01*
G01X80049D01*
G03X79799Y370217I0J-250D01*
G01Y311644D01*
G03X81086Y308537I4394J0D01*
G01X127956Y261667D01*
X127961D01*
X130016Y259607D01*
X130386Y259237D01*
G02X131499Y256550I-2687J-2687D01*
G01Y252676D01*
G03X132649Y249900I3926J0D01*
G01X139249Y243300D01*
G03X140335Y242850I1086J1086D01*
G01X148420D01*
G03X149999Y243504I0J2233D01*
G01X26399Y423322D02*
Y423859D01*
G02X27099Y424559I700J0D01*
G01X30170D01*
G02X31399Y424050I0J-1738D01*
G01X77399Y378050D01*
G02X78499Y375394I-2656J-2656D01*
G01Y311643D01*
G03X80166Y307617I5695J0D01*
G01X119554Y268229D01*
X127415Y260367D01*
X127421D01*
X129289Y258494D01*
X129468Y258315D01*
G02X130199Y256550I-1765J-1765D01*
G01Y252675D01*
G03X131356Y249396I5226J1D01*
G03X131729Y248980I4072J3276D01*
G01X138329Y242380D01*
G03X140334Y241550I2005J2007D01*
G01X148475D01*
G02X149199Y241250I0J-1024D01*
G01X149489Y240960D01*
G02X149999Y239729I-1231J-1231D01*
G01X26492Y439350D02*
G02X29099Y440212I2607J-3511D01*
G01X35179D01*
G02X35385Y440006I0J-206D01*
G03X35591Y439800I206J0D01*
G01X37579D01*
G03X37785Y440006I0J206D01*
G02X37991Y440212I206J0D01*
G01X153699D01*
G03X156571Y440652I2J9582D01*
G01X163985Y442877D01*
G03X170055Y445427I-8844J29551D01*
G02X170161Y445484I2582J-4675D01*
G01X171848Y446905D01*
X171849D01*
X180630Y454302D01*
X181279Y454693D01*
X181877Y454932D01*
X181881D01*
X182339Y455076D01*
X182810Y455224D01*
X834463Y659784D01*
G02X835871Y660000I1408J-4484D01*
G01X849603D01*
G02X852925Y658623I-1J-4699D01*
G01X863698Y647850D01*
G03X866636Y646633I2938J2938D01*
G01X877079D01*
G02X877859Y646310I0J-1103D01*
G01X878596Y645573D01*
G01X26599Y442749D02*
G03X29126Y441512I2601J2113D01*
G01X153699D01*
G03X156182Y441893I0J8281D01*
G01X163612Y444122D01*
G03X169426Y446565I-8473J28305D01*
G01X171373Y448205D01*
X171374D01*
X179844Y455342D01*
X179869Y455363D01*
X180699Y455862D01*
X180754Y455884D01*
X181439Y456157D01*
X181843Y456317D01*
X181949D01*
X834074Y661025D01*
G02X835871Y661300I1796J-5725D01*
G01X849603D01*
G02X853845Y659543I0J-5999D01*
G01X864618Y648770D01*
G03X866639Y647933I2021J2021D01*
G01X876521D01*
G03X877648Y648400I0J1594D01*
G01X878596Y649348D01*
G01X878233Y1051095D02*
X878232Y1051216D01*
G03X876837Y1052183I-1033J0D01*
G02X875000Y1051850I-1837J4902D01*
G01X872749D01*
G02X870379Y1052830I-3J3349D01*
G01X870182Y1053027D01*
G02X869138Y1055550I2523J2522D01*
G01Y1064206D01*
G03X868710Y1065239I-1459J1D01*
G01X868593Y1065355D01*
G03X867280Y1065899I-1314J-1314D01*
G01X781490D01*
G03X775339Y1063350I1J-8699D01*
G01X179943Y467954D01*
X179942D01*
X179843Y467855D01*
G02X172226Y464700I-7618J7619D01*
G01X50408D01*
G03X45169Y462530I0J-7409D01*
G01X40169Y457530D01*
Y457531D01*
G02X36376Y455959I-3795J3794D01*
G01X28008D01*
G03X26899Y454850I0J-1109D01*
G01X26799Y458497D02*
G03X28037Y457259I1238J0D01*
G01X36375D01*
G03X39250Y458450I0J4066D01*
G01X44249Y463449D01*
X44250D01*
G02X50409Y466000I6158J-6158D01*
G01X172225D01*
G03X178924Y468775I0J9474D01*
G01X179403Y469254D01*
X179404D01*
X774419Y1064270D01*
G02X781489Y1067199I7071J-7071D01*
G01X867281D01*
G02X869510Y1066277I-1J-3158D01*
G01X869627Y1066161D01*
G02X870438Y1064205I-1948J-1954D01*
G01Y1055550D01*
G03X871102Y1053947I2267J0D01*
G01X871299Y1053750D01*
G03X872748Y1053150I1449J1449D01*
G01X874999D01*
G03X877781Y1054303I-1J3935D01*
G01X877964Y1054485D01*
G01X878054Y1456450D02*
G03X877054Y1457450I-1000J0D01*
G01X871650D01*
G02X868149Y1458900I0J4951D01*
G01X857349Y1469700D01*
G03X853607Y1471250I-3742J-3742D01*
G01X835443D01*
G03X833149Y1470300I0J-3244D01*
G01X818949Y1456100D01*
X818955Y1456096D01*
X818212Y1455180D01*
X65989Y527050D01*
X65252Y526306D01*
X65198Y526249D01*
X43699Y504750D01*
G02X39964Y503203I-3735J3735D01*
G01X27636D01*
G03X26399Y501966I0J-1237D01*
G01X877853Y1459991D02*
G02X876612Y1458750I-1241J0D01*
G01X871156D01*
G02X869418Y1459470I0J2458D01*
G01X858487Y1470401D01*
G03X853299Y1472550I-5188J-5188D01*
G01X835443D01*
G03X832229Y1471219I-1J-4544D01*
G01X818030Y1457020D01*
X817202Y1455998D01*
X65811Y528896D01*
X64279Y527169D01*
X42529Y505419D01*
G02X40318Y504503I-2211J2211D01*
G01X28999D01*
G02X26674Y505466I0J3288D01*
G01X26399Y505741D01*
G01X866914Y1861840D02*
Y1862634D01*
G03X865999Y1863549I-915J0D01*
G01X863498D01*
G03X858815Y1861610I0J-6625D01*
G01X857881Y1860676D01*
G03X857822Y1860600I284J-281D01*
G01X817226Y1793374D01*
X813914Y1787894D01*
X292455Y924404D01*
X196628Y761569D01*
X173941Y728157D01*
X163141Y710272D01*
X160430Y705784D01*
X158893Y703238D01*
X127954Y652007D01*
X125902Y648609D01*
X84499Y580050D01*
X40409Y520331D01*
X40398Y520330D01*
X40108Y520045D01*
X38785Y518722D01*
G02X36499Y517775I-2286J2286D01*
G01X866914Y1865615D02*
G02X865067Y1864850I-1847J1847D01*
G01X863498D01*
G03X857895Y1862530I0J-7926D01*
G01X856960Y1861594D01*
G03X856708Y1861271I1204J-1199D01*
G01X815549Y1793112D01*
X812802Y1788567D01*
X291338Y925070D01*
X195529Y762265D01*
X172846Y728859D01*
X161491Y710056D01*
X159317Y706457D01*
X157779Y703910D01*
X126840Y652679D01*
X126831Y652663D01*
X125168Y649909D01*
X83417Y580774D01*
X39487Y521271D01*
Y521259D01*
X39196Y520973D01*
X38136Y519913D01*
G02X37136I-500J500D01*
G02X36499Y521451I1538J1538D01*
G01Y521550D01*
G01X39217Y554750D02*
X37517Y553050D01*
X33799D01*
G01X33699Y561850D02*
X34149Y561450D01*
X37849D01*
G01X36499Y566350D02*
X36199Y566050D01*
X31549D01*
G01X28808Y593150D02*
X32341D01*
X32505Y592986D01*
G01X32300Y597800D02*
X29951D01*
X28700Y596549D01*
G01X27499Y620203D02*
G02X30341Y621380I2842J-2842D01*
G01X47689D01*
G03X64999Y628550I0J24480D01*
G03X67499Y634586I-6036J6036D01*
G01Y667156D01*
G02X69518Y672030I6893J0D01*
G01X139768Y742280D01*
Y742281D01*
G03X140867Y744932I-2652J2653D01*
G01Y766866D01*
G02X142336Y770412I5015J0D01*
G01X183037Y811113D01*
G03X184999Y815850I-4739J4738D01*
G01Y1173709D01*
G03X184108Y1175860I-3042J0D01*
G01X162958Y1197010D01*
G02X161399Y1200774I3764J3764D01*
G01Y1374674D01*
G03X160498Y1376849I-3076J0D01*
G01X131698Y1405649D01*
G02X130049Y1409630I3981J3981D01*
G01Y1447624D01*
G03X128152Y1452204I-6477J0D01*
G01X115702Y1464654D01*
G02X113499Y1469973I5319J5319D01*
G01Y1647666D01*
G02X116599Y1655150I10584J0D01*
G01X145198Y1683749D01*
G03X148799Y1692443I-8693J8693D01*
G01Y1799801D01*
G03X146721Y1804819I-7098J0D01*
G01X146525Y1805015D01*
X146524Y1805014D01*
X134765Y1816774D01*
G02X132900Y1821277I4503J4503D01*
G01Y1860421D01*
G02X133421Y1861679I1779J0D01*
G01X133564Y1861822D01*
G02X135200Y1862500I1636J-1635D01*
G01X136300D01*
G02X137488Y1862008I0J-1680D01*
G01X137999Y1861497D01*
G01Y1865151D02*
X137247Y1864400D01*
G02X135800Y1863800I-1448J1447D01*
G01X135199D01*
G03X132644Y1862742I0J-3614D01*
G01X132501Y1862599D01*
X132502Y1862598D01*
G03X131600Y1860420I2177J-2177D01*
G01Y1821278D01*
G03X133846Y1815855I7668J-1D01*
G01X133845Y1815854D01*
X145801Y1803899D01*
G02X147499Y1799800I-4099J-4099D01*
G01Y1692442D01*
G02X144279Y1684669I-10994J1D01*
G01X115679Y1656069D01*
G03X112199Y1647667I8404J-8403D01*
G01Y1469973D01*
G03X114783Y1463734I8822J-1D01*
G01X127233Y1451284D01*
G02X128748Y1447624I-3662J-3659D01*
G01X128749Y1447625D01*
Y1409629D01*
G03X130778Y1404730I6930J1D01*
G01X159578Y1375930D01*
G02X160099Y1374673I-1255J-1257D01*
G01Y1200774D01*
G03X162039Y1196090I6623J-1D01*
G01X183188Y1174941D01*
G02X183699Y1173708I-1231J-1233D01*
G01Y815851D01*
G02X182117Y812032I-5401J0D01*
G01X141499Y771414D01*
G03X139567Y766750I4664J-4664D01*
G01Y744933D01*
G02X138849Y743200I-2451J0D01*
G01X68598Y672949D01*
G03X66199Y667157I5794J-5793D01*
G01Y634585D01*
X66198Y634586D01*
G02X64079Y629470I-7235J0D01*
G02X47689Y622680I-16391J16389D01*
G01X30341D01*
G02X27499Y623857I0J4019D01*
G01X35766Y602721D02*
X33189D01*
X32200Y603710D01*
G01X35157Y608117D02*
X35117D01*
X34022Y607022D01*
X31678D01*
X31598Y607102D01*
G01X85341Y1752245D02*
X86056Y1751530D01*
G03X87258Y1750892I1641J1641D01*
G03X87699Y1750850I440J2283D01*
G01X89998D01*
G02X90700Y1750800I3J-4917D01*
G02X93476Y1749411I-699J-4866D01*
G01X94468Y1748419D01*
X94467Y1748418D01*
X97074Y1745812D01*
G02X98548Y1742250I-3563J-3560D01*
G01X98549D01*
Y1694463D01*
G03X99944Y1691095I4763J0D01*
G01X104144Y1686895D01*
G02X105299Y1684107I-2788J-2788D01*
G01Y1467232D01*
G03X107168Y1462720I6381J0D01*
G01X120018Y1449870D01*
G02X122649Y1443518I-6352J-6352D01*
G01Y1406090D01*
G03X123964Y1402915I4490J0D01*
G01X153164Y1373715D01*
G02X153999Y1371699I-2016J-2016D01*
G01Y1197516D01*
G03X155424Y1194076I4865J0D01*
G01X176074Y1173426D01*
G02X177299Y1170469I-2957J-2957D01*
G01Y818454D01*
G02X175453Y813997I-6305J1D01*
G01X134302Y772846D01*
G03X133314Y770461I2385J-2385D01*
G01Y748849D01*
G02X132380Y746590I-3194J-2D01*
G01X131419Y745630D01*
X61669Y675880D01*
G03X59499Y670641I5239J-5239D01*
G01Y644378D01*
G02X57499Y639550I-6828J0D01*
G02X51649Y637127I-5850J5850D01*
G01X29410D01*
G03X26568Y635950I0J-4019D01*
G01X85194Y1748848D02*
G02X86889Y1749550I1695J-1695D01*
G01X89999D01*
G02X92556Y1748491I0J-3616D01*
G01X95198Y1745849D01*
X96154Y1744892D01*
G02X97249Y1742250I-2642J-2643D01*
G01Y1738218D01*
G02X96974Y1737943I-275J0D01*
G03X96699Y1737668I0J-275D01*
G01Y1735818D01*
G03X96974Y1735543I275J0D01*
G02X97249Y1735268I0J-275D01*
G01Y1733418D01*
G02X96974Y1733143I-275J0D01*
G03X96699Y1732868I0J-275D01*
G01Y1731018D01*
G03X96974Y1730743I275J0D01*
G02X97249Y1730468I0J-275D01*
G01Y1728618D01*
G02X96974Y1728343I-275J0D01*
G03X96699Y1728068I0J-275D01*
G01Y1726218D01*
G03X96974Y1725943I275J0D01*
G02X97249Y1725668I0J-275D01*
G01Y1694463D01*
G03X99025Y1690175I6063J-1D01*
G01X103224Y1685976D01*
G02X103999Y1684106I-1868J-1870D01*
G01Y1599735D01*
G02X103750Y1599486I-249J0D01*
G01X103749D01*
G03X103500Y1599237I0J-249D01*
G01Y1597335D01*
G03X103749Y1597086I249J0D01*
G01X103750D01*
G02X103999Y1596837I0J-249D01*
G01Y1594935D01*
G02X103750Y1594686I-249J0D01*
G01X103749D01*
G03X103500Y1594437I0J-249D01*
G01Y1592535D01*
G03X103749Y1592286I249J0D01*
G01X103750D01*
G02X103999Y1592037I0J-249D01*
G01Y1590135D01*
G02X103750Y1589886I-249J0D01*
G01X103749D01*
G03X103500Y1589637I0J-249D01*
G01Y1587735D01*
G03X103749Y1587486I249J0D01*
G01X103750D01*
G02X103999Y1587237I0J-249D01*
G01Y1467231D01*
G03X106248Y1461801I7681J1D01*
G01X119099Y1448950D01*
G02X121349Y1443518I-5433J-5432D01*
G01Y1406090D01*
G03X123045Y1401995I5790J-1D01*
G01X152245Y1372795D01*
G02X152698Y1371699I-1098J-1095D01*
G01X152699Y1371700D01*
Y1197515D01*
G03X154504Y1193157I6165J1D01*
G01X175154Y1172507D01*
G02X175999Y1170468I-2037J-2039D01*
G01Y818455D01*
G02X174533Y814916I-5005J0D01*
G01X133382Y773765D01*
G03X132014Y770462I3305J-3304D01*
G01Y748849D01*
G02X131460Y747510I-1893J-1D01*
G01X130499Y746550D01*
X60749Y676800D01*
X60750Y676799D01*
G03X58199Y670640I6158J-6158D01*
G01Y644379D01*
G02X56579Y640470I-5527J1D01*
G02X51650Y638427I-4931J4929D01*
G01X29410D01*
G02X26568Y639604I0J4019D01*
G01X86890Y1346635D02*
G03X89509Y1345550I2619J2619D01*
G01X92792D01*
G02X93999Y1345050I0J-1707D01*
G02X95079Y1342443I-2607J-2607D01*
G01Y1059020D01*
G03X96607Y1055331I5217J0D01*
G01X114360Y1037578D01*
G02X117499Y1030000I-7578J-7578D01*
G01Y751253D01*
G02X115419Y746230I-7105J0D01*
G01X53119Y683930D01*
G03X50999Y678812I5118J-5118D01*
G01Y658878D01*
G02X48999Y654050I-6828J0D01*
G02X46585Y653050I-2414J2414D01*
G01X29376D01*
G03X26737Y651957I0J-3732D01*
G01X86890Y1342860D02*
G02X90246Y1344250I3356J-3356D01*
G01X92791D01*
G02X93079Y1344130I0J-406D01*
G02X93779Y1342442I-1686J-1688D01*
G01Y1331745D01*
G02X93439Y1331405I-340J0D01*
G03X93099Y1331065I0J-340D01*
G01Y1329345D01*
G03X93439Y1329005I340J0D01*
G02X93779Y1328665I0J-340D01*
G01Y1326741D01*
G02X93539Y1326501I-240J0D01*
G03X93299Y1326261I0J-240D01*
G01Y1324341D01*
G03X93539Y1324101I240J0D01*
G02X93779Y1323861I0J-240D01*
G01Y1059500D01*
G03X96027Y1054073I7675J0D01*
G01X112901Y1037199D01*
X112900Y1037198D01*
X113440Y1036658D01*
G02X116199Y1029999I-6657J-6659D01*
G01Y751254D01*
G02X114499Y747150I-5804J0D01*
G01X52199Y684850D01*
X52200Y684849D01*
G03X49699Y678813I6037J-6038D01*
G01Y658879D01*
G02X48079Y654970I-5527J1D01*
G02X46584Y654350I-1495J1493D01*
G01X27982D01*
G02X27499Y654550I0J683D01*
G02X26999Y655757I1207J1207D01*
G01Y656550D01*
G01X85999Y940429D02*
G03X87221Y939923I1222J1222D01*
G01X89262D01*
G02X92169Y938719I1J-4110D01*
G01X100818Y930070D01*
G02X102449Y926132I-3937J-3937D01*
G01Y759665D01*
G02X99618Y752830I-9665J-1D01*
G01X43418Y696630D01*
G03X41592Y694354I9461J-9461D01*
G03X39499Y687169I11287J-7185D01*
G01Y673550D01*
G02X34999Y669050I-4500J0D01*
G01X28999D01*
G03X27687Y667738I0J-1312D01*
G01Y667447D01*
G01X86399Y937050D02*
G02Y938350I650J650D01*
G02X87058Y938623I659J-659D01*
G01X89262D01*
G02X91249Y937800I0J-2810D01*
G01X99899Y929150D01*
G02X101149Y926132I-3018J-3018D01*
G01Y917497D01*
G02X100875Y917223I-274J0D01*
G01X100874D01*
G03X100600Y916949I0J-274D01*
G01Y915097D01*
G03X100874Y914823I274J0D01*
G01X100875D01*
G02X101149Y914549I0J-274D01*
G01Y912697D01*
G02X100875Y912423I-274J0D01*
G01X100874D01*
G03X100600Y912149I0J-274D01*
G01Y910297D01*
G03X100874Y910023I274J0D01*
G01X100875D01*
G02X101149Y909749I0J-274D01*
G01Y802752D01*
G02X100925Y802528I-224J0D01*
G01X100924D01*
G03X100700Y802304I0J-224D01*
G01Y800352D01*
G03X100924Y800128I224J0D01*
G01X100925D01*
G02X101149Y799904I0J-224D01*
G01Y797952D01*
G02X100925Y797728I-224J0D01*
G01X100924D01*
G03X100700Y797504I0J-224D01*
G01Y795552D01*
G03X100924Y795328I224J0D01*
G01X100925D01*
G02X101149Y795104I0J-224D01*
G01Y786060D01*
G02X100925Y785836I-224J0D01*
G01X100924D01*
G03X100700Y785612I0J-224D01*
G01Y783660D01*
G03X100924Y783436I224J0D01*
G01X100925D01*
G02X101149Y783212I0J-224D01*
G01Y759665D01*
G02X98699Y753750I-8365J0D01*
G01X42498Y697549D01*
X42499D01*
G03X40496Y695052I10381J-10379D01*
G03X38199Y687170I12383J-7884D01*
G01Y673550D01*
G02X34999Y670350I-3200J0D01*
G01X29500D01*
G02X27687Y671101I0J2564D01*
G01X77758Y1357742D02*
X25000D01*
G01X25507Y1372045D02*
X25660Y1371892D01*
G03X28499Y1370716I2839J2839D01*
G01X80279D01*
G03X83499Y1372050I-1J4555D01*
G01X92585Y1381136D01*
G02X95999Y1382550I3414J-3414D01*
G01X100378D01*
G02X103999Y1381050I0J-5121D01*
G02X104922Y1379044I-2250J-2250D01*
G01Y1377243D01*
G02X104200Y1375500I-2465J0D01*
G02X100984Y1374168I-3216J3216D01*
G01X99235D01*
G03X97229Y1373337I0J-2837D01*
G01X25558Y1368447D02*
G02X27897Y1369416I2339J-2339D01*
G01X30194D01*
G02X30502Y1369108I0J-308D01*
G03X30810Y1368800I308J0D01*
G01X32594D01*
G03X32902Y1369108I0J308D01*
G02X33210Y1369416I308J0D01*
G01X34994D01*
G02X35302Y1369108I0J-308D01*
G03X35610Y1368800I308J0D01*
G01X37394D01*
G03X37702Y1369108I0J308D01*
G02X38010Y1369416I308J0D01*
G01X52004D01*
G02X52262Y1369158I0J-258D01*
G03X52520Y1368900I258J0D01*
G01X54404D01*
G03X54662Y1369158I0J258D01*
G02X54920Y1369416I258J0D01*
G01X56804D01*
G02X57062Y1369158I0J-258D01*
G03X57320Y1368900I258J0D01*
G01X59204D01*
G03X59462Y1369158I0J258D01*
G02X59720Y1369416I258J0D01*
G01X63600D01*
G02X63808Y1369208I0J-208D01*
G03X64016Y1369000I208J0D01*
G01X66000D01*
G03X66208Y1369208I0J208D01*
G02X66416Y1369416I208J0D01*
G01X80278D01*
G03X84419Y1371130I2J5856D01*
G01X93505Y1380216D01*
G02X95998Y1381250I2495J-2493D01*
G01X100377D01*
G02X103079Y1380130I0J-3820D01*
G02X103623Y1378944I-1331J-1328D01*
G01X103622D01*
Y1377244D01*
G02X103280Y1376420I-1164J0D01*
G02X100985Y1375468I-2297J2295D01*
G01X98019D01*
G02X97700Y1375600I0J451D01*
G02X97000Y1377290I1690J1690D01*
G01Y1377600D01*
G01X117390Y1426201D02*
X116778Y1426813D01*
G03X114999Y1427550I-1779J-1779D01*
G01X106369D01*
G02X100456Y1430052I130J8545D01*
G01X99978Y1430530D01*
X99979Y1430531D01*
X48479Y1482031D01*
X48209Y1482302D01*
G02X44999Y1490050I7748J7749D01*
G01Y1508176D01*
G03X42839Y1513391I-7375J0D01*
G01X39089Y1517141D01*
X38414Y1517815D01*
G03X35499Y1519023I-2915J-2913D01*
G01X34499D01*
G03X32241Y1518087I1J-3194D01*
G01X31999Y1517846D01*
G01X117390Y1429976D02*
G02X114672Y1428850I-2718J2718D01*
G01X106499D01*
G02X106498Y1428849I-5124J5123D01*
G02X101376Y1430972I2J7245D01*
G01X51648Y1480700D01*
X51649Y1480701D01*
X49400Y1482950D01*
X49130Y1483221D01*
X49126Y1483225D01*
G02X47173Y1486038I6830J6827D01*
G01X47172Y1486041D01*
G02X46302Y1489823I8784J4012D01*
G01X46301Y1489847D01*
G02X46299Y1490051I8568J186D01*
G01Y1508176D01*
G03X43759Y1514311I-8675J2D01*
G01X40008Y1518061D01*
X39334Y1518735D01*
G03X35499Y1520323I-3834J-3834D01*
G01X34499D01*
G02X32241Y1521259I1J3194D01*
G01X31999Y1521500D01*
G01X60000Y1535500D02*
X59885Y1535615D01*
X41905D01*
X40300Y1534010D01*
Y1533854D01*
X39146Y1532700D01*
X36863D01*
X33763Y1529600D01*
X30099D01*
X24199Y1523700D01*
G01X29631Y1533063D02*
X32532D01*
X35919Y1536450D01*
X40457D01*
X42057Y1538050D01*
X76242D01*
X77842Y1536450D01*
X85000D01*
G01X74400Y1574800D02*
X40300D01*
X39000Y1573500D01*
G01X33599Y1600200D02*
Y1599296D01*
X46425Y1586470D01*
G01X37173Y1583074D02*
X39185Y1581062D01*
X72000D01*
X72200Y1580862D01*
X78176D01*
X84229Y1574809D01*
Y1567329D01*
X80529Y1563629D01*
Y1557609D01*
X79000Y1556080D01*
Y1555500D01*
G01X65000Y1697500D02*
X30500D01*
G01X85599Y1797350D02*
X82899Y1794650D01*
X68999D01*
X66949Y1796700D01*
X46349D01*
X43478Y1799571D01*
X38878D01*
G01X47899Y1798650D02*
X41426Y1805123D01*
X34599D01*
G01X62300Y1789650D02*
X41974D01*
X37574Y1794050D01*
G01X31811Y1790271D02*
X34032Y1788050D01*
X60930D01*
X61430Y1787550D01*
X68469D01*
X99999Y1756020D01*
Y1753575D01*
G01X40478Y1795820D02*
X40333D01*
X39003Y1797150D01*
X32099D01*
G01X29599Y1844350D02*
X35145D01*
X44899Y1834596D01*
Y1833104D01*
X43145Y1831350D01*
X33199D01*
X30002Y1828153D01*
X28550D01*
G01X96600Y1826000D02*
X96100Y1825500D01*
X89005D01*
X88765Y1825740D01*
X42338D01*
X37648Y1821050D01*
X29899D01*
G01X35876Y1812350D02*
X42599D01*
X48049Y1806900D01*
X90148D01*
X91499Y1805549D01*
G01X34129Y1815267D02*
X43002Y1824140D01*
X76309D01*
X83349Y1817100D01*
X86649D01*
G01X40299Y1828750D02*
X36399D01*
G01D02*
X33157Y1825508D01*
X26657D01*
X26099Y1824950D01*
G01X57300Y452700D02*
X61300D01*
X61400Y452600D01*
G01X43300Y806300D02*
X51100D01*
G01X89000Y816500D02*
X88000D01*
X82150Y810650D01*
X52450D01*
X49900Y813200D01*
G01X56281Y801350D02*
X56181Y801450D01*
X52299D01*
G01X62405Y820300D02*
X62432Y820273D01*
Y818778D01*
X59800Y816146D01*
Y812750D01*
G01X54074Y815750D02*
X54000Y816200D01*
Y819900D01*
G01X50399Y836250D02*
X44899D01*
G01X58699Y837250D02*
X57899Y838050D01*
X54799D01*
G01X68860Y838706D02*
X64599D01*
X61855Y841450D01*
X50399D01*
G01X69499Y842950D02*
X66145D01*
X64045Y845050D01*
X55999D01*
X55299Y844350D01*
G01X47200Y848431D02*
X71243D01*
X72362Y849550D01*
G01X44299Y1550950D02*
X42299Y1548950D01*
X41599D01*
X41396Y1548747D01*
X41325D01*
G01X60000Y1535500D02*
X61191Y1534309D01*
X98144D01*
G01X46425Y1586470D02*
X48033Y1584862D01*
X74638D01*
X74800Y1584700D01*
G01X82329Y1568117D02*
Y1574021D01*
X77388Y1578962D01*
X60700D01*
G01X82429Y1555500D02*
Y1562841D01*
X86129Y1566541D01*
Y1575597D01*
X78964Y1582762D01*
X73100D01*
X72900Y1582962D01*
X44038D01*
X40200Y1586800D01*
G01X46199Y1783050D02*
X48299D01*
X55299Y1776050D01*
X62399D01*
G01X110099Y1759875D02*
Y1758866D01*
X101408Y1750175D01*
X96211D01*
X78236Y1768150D01*
X48459D01*
X47604Y1769005D01*
G01X68999Y1773550D02*
X49299D01*
X47499Y1775350D01*
G01X109499Y1712213D02*
Y1734550D01*
X111899Y1736950D01*
Y1776746D01*
X95895Y1792750D01*
X49399D01*
X48099Y1791450D01*
X48049D01*
G01X61009Y1822340D02*
X70777D01*
X82567Y1810550D01*
X115729D01*
X121151Y1805128D01*
G01X46499Y1836550D02*
X46999Y1836050D01*
X50199D01*
Y1836052D01*
G01X47166Y1839884D02*
Y1840217D01*
X49616Y1842667D01*
G01X68800Y454300D02*
X67600Y455500D01*
X65000D01*
G01X65599Y514250D02*
Y511950D01*
X75699Y501850D01*
Y501804D01*
X82453Y495050D01*
X123999D01*
G01X66500Y543000D02*
Y545000D01*
X68000Y546500D01*
G01X72500Y545000D02*
X73000Y545500D01*
Y548700D01*
G01X80499Y664550D02*
X80206D01*
G02X78999Y665050I0J1707D01*
G02X78768Y665608I558J558D01*
G01Y667799D01*
G02X79299Y669010I1809J-71D01*
G01X82418Y672130D01*
G02X83915Y672750I1497J-1497D01*
G01X90457D01*
G03X93031Y673816I-1J3642D01*
G01X147032Y727817D01*
G03X148851Y732209I-4394J4393D01*
G01Y764169D01*
G02X150470Y768079I5529J1D01*
G01X150670Y768278D01*
X190521Y808129D01*
G03X192399Y812663I-4534J4534D01*
G01Y1175906D01*
G03X190892Y1179544I-5145J0D01*
G01X170442Y1199994D01*
G02X168799Y1203961I3967J3967D01*
G01Y1376798D01*
G03X167231Y1380584I-5353J1D01*
G01X139382Y1408433D01*
G02X137449Y1413100I4667J4667D01*
G01Y1446161D01*
X137450Y1446162D01*
Y1451938D01*
X137449Y1451939D01*
Y1454210D01*
G02X138149Y1455900I2390J0D01*
G01X138150D01*
X138749Y1456499D01*
G02X139874Y1457156I1811J-1810D01*
G02X140559Y1457250I687J-2467D01*
G01X141450D01*
G02X142597Y1456775I0J-1622D01*
G01X142999Y1456373D01*
G01X76999Y664550D02*
G03X77471Y665690I-1140J1140D01*
G01Y667851D01*
G02X78379Y669930I3108J-120D01*
G01X78399Y669950D01*
X81498Y673050D01*
G02X83915Y674050I2416J-2418D01*
G01X90456D01*
G03X92112Y674736I0J2342D01*
G01X129892Y712516D01*
G03Y712854I-169J169D01*
G02Y713192I169J169D01*
G01X131252Y714552D01*
G02X131590I169J-169D01*
G03X131928I169J169D01*
G01X146112Y728736D01*
G03X147551Y732210I-3474J3474D01*
G01Y764170D01*
G02X149551Y768997I6827J-1D01*
G01Y768998D01*
X189601Y809048D01*
Y809049D01*
G03X191099Y812662I-3613J3615D01*
G01Y1175905D01*
G03X189972Y1178625I-3845J0D01*
G01X169523Y1199074D01*
G02X167499Y1203961I4886J4886D01*
G01Y1376798D01*
G03X166312Y1379664I-4053J0D01*
G01X138463Y1407513D01*
G02X136149Y1413100I5586J5586D01*
G01Y1446700D01*
X136150Y1446701D01*
Y1451399D01*
X136149Y1451400D01*
Y1454210D01*
G02X137230Y1456820I3690J0D01*
G01X137829Y1457419D01*
G02X140560Y1458550I2730J-2730D01*
G01X141450D01*
G03X142900Y1460000I0J1450D01*
G01X90000Y826000D02*
X79691D01*
X73600Y832091D01*
Y833966D01*
X68860Y838706D01*
G01X90500Y831500D02*
X76454D01*
X75200Y832754D01*
Y834912D01*
X69606Y840506D01*
X66043D01*
X63499Y843050D01*
G01X74220Y854150D02*
X70601Y850531D01*
X61600D01*
G01X72000Y1013400D02*
Y1017700D01*
X72300Y1018000D01*
G01X66000Y1020350D02*
X63273Y1023077D01*
Y1023974D01*
G01X66499Y1025050D02*
X70499D01*
X70999Y1025550D01*
G01X99899Y1539850D02*
X98199Y1541550D01*
X81999D01*
G01X100000Y1546650D02*
X72599D01*
G01X90324Y1538800D02*
X80149D01*
X78399Y1540550D01*
X70099D01*
G01X78600Y1561900D02*
Y1566200D01*
X78400Y1566400D01*
G01X75000Y1561800D02*
Y1557900D01*
X74600Y1557500D01*
G01X80400Y1571766D02*
X80379Y1571787D01*
Y1573001D01*
X78462Y1574918D01*
G01X65000Y1697500D02*
X72400D01*
X74500Y1695400D01*
Y1692000D01*
G01X62399Y1776050D02*
X72350D01*
X74400Y1778100D01*
G01X99199Y1761899D02*
X71448Y1789650D01*
X62300D01*
G01X101399Y1784700D02*
X101799Y1784300D01*
Y1752829D01*
X100745Y1751775D01*
X96874D01*
X75099Y1773550D01*
X68999D01*
G01X88005Y996217D02*
Y995095D01*
X90000Y993100D01*
G01X93500Y1000300D02*
Y997000D01*
X92600Y996100D01*
G01X85000Y1536450D02*
X100800D01*
G01X96200Y1550100D02*
X95650Y1549550D01*
X91399D01*
G01X91499Y1805549D02*
X101500Y1795548D01*
Y1791427D01*
X135899Y1757028D01*
Y1722550D01*
G01X97999Y1843050D02*
X97116Y1842167D01*
Y1839908D01*
X103920Y1833104D01*
G01X176799Y493850D02*
X175599Y495050D01*
X123999D01*
G01X149000Y537500D02*
X111700D01*
X106000Y543200D01*
G01X109400D02*
X112184Y540416D01*
X150750D01*
G01X112699Y1058974D02*
X112500Y1059173D01*
Y1062600D01*
X105600Y1069500D01*
G01X109499Y1080550D02*
X110050D01*
X116248Y1086748D01*
X158446D01*
X159794Y1085400D01*
X164700D01*
G01X109499Y1080550D02*
X105499D01*
G01X106718Y1076050D02*
X109099D01*
X110490Y1074659D01*
X111140D01*
G01X123999Y1102550D02*
X123599Y1102350D01*
X120982Y1099733D01*
G01X108999Y1102050D02*
X109499Y1101550D01*
Y1098350D01*
G01X112753Y1716613D02*
X112890Y1716750D01*
X116499D01*
G01X123749Y1711550D02*
X127049Y1708250D01*
X127499D01*
G01X141999Y1764550D02*
Y1784280D01*
X121151Y1805128D01*
G01X127499Y1708250D02*
X138245D01*
X142799Y1712804D01*
Y1714253D01*
X143300Y1714754D01*
Y1716246D01*
X142399Y1717147D01*
Y1746420D01*
X143799Y1747820D01*
Y1793225D01*
X103920Y1833104D01*
G01X141499Y427550D02*
X142999D01*
X144999Y425550D01*
G01X131999Y1710050D02*
X131599Y1710450D01*
Y1714150D01*
G01X135499Y1710150D02*
X135899Y1710550D01*
Y1722550D01*
G01X188000Y484500D02*
X187900Y484400D01*
X184200D01*
G01X200799Y896600D02*
X200809Y896610D01*
X204699D01*
G01X247252Y1826803D02*
X201499Y1781050D01*
G01X215500Y893610D02*
X212740D01*
X211750Y894600D01*
G01X285499Y1930050D02*
X288399Y1927150D01*
Y1867950D01*
X247252Y1826803D01*
G01X253871Y291410D02*
Y302422D01*
X280345Y328896D01*
G01X284764Y738315D02*
X254499Y708050D01*
Y697700D01*
G01X261999Y1516050D02*
X275674D01*
X282499Y1522875D01*
Y1538550D01*
X290411Y1546462D01*
G01X284999Y338650D02*
Y342750D01*
G01X301249Y346050D02*
X297499D01*
X280345Y328896D01*
G01X285499Y745050D02*
Y748815D01*
X285264Y749050D01*
G01X310999Y757050D02*
X307499Y753550D01*
X297999D01*
X284764Y740315D01*
Y738315D01*
G01X310249Y1569800D02*
X310499Y1569550D01*
Y1566550D01*
X290411Y1546462D01*
G01X283499Y1556050D02*
X284690D01*
X285299Y1556659D01*
X285908D01*
X286831Y1557582D01*
X286868D01*
G01X288709Y1948042D02*
X289999Y1946752D01*
Y1820550D01*
X299995Y1810554D01*
G01X348499Y1762050D02*
X299995Y1810554D01*
G01X326499Y334054D02*
X326003D01*
X323499Y331550D01*
G01X327999Y740550D02*
X329519D01*
X331263Y742294D01*
G01X331622Y1944767D02*
X331499Y1944450D01*
Y1940750D01*
G01X341499Y67110D02*
X337799D01*
G01X353499Y1710450D02*
Y1710550D01*
X363499Y1720550D01*
X526499D01*
X740999Y1935050D01*
X755999D01*
G01X365499Y86550D02*
X373499D01*
X390411Y69638D01*
G01X381999Y53550D02*
Y53350D01*
X379768Y51119D01*
X378428D01*
G01X394199Y45050D02*
Y65850D01*
X390411Y69638D01*
G01X381999Y57050D02*
X382999D01*
X385499Y59550D01*
G01Y1735050D02*
X525474D01*
X732974Y1942550D01*
X756499D01*
G01X711652Y1822109D02*
X741591D01*
X760200Y1803500D01*
X793000D01*
G01X795849Y1805500D02*
X760888D01*
X740884Y1825504D01*
X711848D01*
G01X771499Y1936550D02*
X769999Y1935050D01*
X755999D01*
G01X794499Y1941050D02*
X792999Y1942550D01*
X756499D01*
G01X772499Y323050D02*
X776199D01*
G01X772873Y326924D02*
Y330624D01*
G01X771105Y722789D02*
X770999Y723050D01*
Y726750D01*
G01X769999Y733050D02*
X774199D01*
G01X771999Y1124550D02*
X771770Y1124321D01*
X768306D01*
G01X772499Y1130050D02*
X774383Y1131934D01*
Y1133235D01*
G01X779499Y1131050D02*
X781403Y1129146D01*
X782672D01*
G01X774542Y1530050D02*
Y1526350D01*
G01X774577Y1533796D02*
X774499Y1534850D01*
Y1537484D01*
X774488Y1537495D01*
G01X771499Y1940050D02*
X775199D01*
G01X791499Y333050D02*
X795199D01*
G01X789999Y336550D02*
Y340250D01*
G01X788999Y736050D02*
X787095Y737954D01*
X785826D01*
G01X791999Y733050D02*
Y729350D01*
G01X792154Y1135926D02*
X795854D01*
G01X789499Y1138050D02*
X788854Y1138926D01*
Y1142626D01*
G01X784499Y1529050D02*
X789099Y1524450D01*
Y1492450D01*
X798149Y1483400D01*
X870649D01*
X883249Y1470800D01*
Y1455300D01*
X861849Y1433900D01*
Y1383500D01*
G01X791499Y1543550D02*
X787799D01*
G01X797699Y1541050D02*
X793999D01*
G01X793000Y1803500D02*
X796537D01*
X802399Y1809362D01*
Y1817699D01*
X807000Y1822300D01*
G01X795849Y1805500D02*
X800499Y1810150D01*
Y1819707D01*
X803500Y1822708D01*
G01X782999Y1937050D02*
Y1917580D01*
X817529Y1883050D01*
X833999D01*
G01X792499Y1949050D02*
Y1950705D01*
X790844Y1952360D01*
G01X917499Y1796550D02*
Y1818050D01*
X869215Y1866335D01*
X868751Y1867453D01*
X867632Y1867917D01*
X852499Y1883050D01*
X833999D01*
G01X861849Y1383500D02*
Y1376050D01*
G01X1004307Y1636102D02*
X971798D01*
X969600Y1638300D01*
G01X1004307Y1651102D02*
X967602D01*
X967600Y1651100D01*
G01X1004307Y1641102D02*
X988102D01*
X986400Y1639400D01*
Y1639302D01*
G01X971558Y1646500D02*
X987456D01*
X988756Y1647800D01*
X990248D01*
X991946Y1646102D01*
X1004307D01*
G01X977500Y1660500D02*
X978400Y1661400D01*
X981546D01*
X981844Y1661102D01*
X1004307D01*
G01X978000Y1668000D02*
Y1668100D01*
X981002Y1671102D01*
X1004307D01*
G54D16*
X68898Y17047D03*
Y190275D03*
Y422559D03*
Y595787D03*
Y828071D03*
Y1001299D03*
Y1233583D03*
Y1406811D03*
Y1639095D03*
Y1812323D03*
X167323Y179803D03*
Y353031D03*
Y585315D03*
Y758543D03*
Y990827D03*
Y1164055D03*
Y1396339D03*
Y1569567D03*
Y1801851D03*
Y1975079D03*
X895669Y179803D03*
Y353031D03*
Y585315D03*
Y758543D03*
Y990827D03*
Y1164055D03*
Y1396339D03*
Y1569567D03*
Y1801851D03*
Y1975079D03*
G54D26*
G01X-53190Y-209897D02*
Y-192397D01*
G01X-44894D02*
X-53190Y-203189D01*
G01X-43584Y-209897D02*
X-49479Y-198231D01*
G01X-35909Y-209897D02*
Y-192397D01*
X-25865Y-209897D01*
Y-192397D01*
G01X-13387Y-209897D02*
X-15134Y-209605D01*
X-16662Y-208439D01*
X-17972Y-206689D01*
X-18846Y-204647D01*
X-19282Y-202314D01*
Y-199980D01*
X-18846Y-197647D01*
X-17972Y-195605D01*
X-16662Y-193856D01*
X-15134Y-192689D01*
X-13387Y-192397D01*
X-11641Y-192689D01*
X-10112Y-193856D01*
X-8802Y-195605D01*
X-7928Y-197647D01*
X-7492Y-199980D01*
Y-202314D01*
X-7928Y-204647D01*
X-8802Y-206689D01*
X-10112Y-208439D01*
X-11641Y-209605D01*
X-13387Y-209897D01*
G01X-472D02*
X8698Y-192397D01*
G01X-472D02*
X8698Y-209897D01*
G01X34310D02*
Y-192397D01*
X38676D01*
X40423Y-193272D01*
X41733Y-194439D01*
X42825Y-196188D01*
X43698Y-198231D01*
X43916Y-201147D01*
X43698Y-204064D01*
X42825Y-206106D01*
X41733Y-207856D01*
X40423Y-209022D01*
X38676Y-209897D01*
X34310D01*
G01X52246D02*
Y-192397D01*
X57705D01*
X59451Y-193272D01*
X60543Y-194439D01*
X60980Y-196772D01*
X60543Y-199106D01*
X59233Y-200564D01*
X57705Y-201439D01*
X52246D01*
G01X57705D02*
X60980Y-209897D01*
G01X71493Y-192397D02*
X76733D01*
G01X74113D02*
Y-209897D01*
G01X71493D02*
X76733D01*
G01X86154Y-192397D02*
X91613Y-209897D01*
X97072Y-192397D01*
G01X113480Y-209897D02*
X104746D01*
Y-192397D01*
X113480D01*
G01X109986Y-200855D02*
X104746D01*
G01X139746Y-209897D02*
Y-192397D01*
X144986D01*
X146733Y-193272D01*
X148043Y-195314D01*
X148480Y-197647D01*
X148043Y-199980D01*
X146951Y-201730D01*
X144986Y-202606D01*
X139746D01*
G01X157246Y-192397D02*
Y-209897D01*
X165980D01*
G01X173654D02*
X179113Y-192397D01*
X184572Y-209897D01*
G01X182606Y-203772D02*
X175619D01*
G01X191591Y-209897D02*
Y-192397D01*
X201635Y-209897D01*
Y-192397D01*
G01X218480Y-209897D02*
X209746D01*
Y-192397D01*
X218480D01*
G01X214986Y-200855D02*
X209746D01*
G01X250859Y-200564D02*
X251733Y-199689D01*
X252388Y-198231D01*
X252825Y-196188D01*
X252388Y-194439D01*
X251515Y-193272D01*
X249986Y-192397D01*
X244091D01*
Y-209897D01*
X251296D01*
X252825Y-208731D01*
X253698Y-206980D01*
X254135Y-204939D01*
X253698Y-202897D01*
X252388Y-201147D01*
X250859Y-200564D01*
X244091D01*
G01X266613Y-209897D02*
X264866Y-209605D01*
X263338Y-208439D01*
X262028Y-206689D01*
X261154Y-204647D01*
X260718Y-202314D01*
Y-199980D01*
X261154Y-197647D01*
X262028Y-195605D01*
X263338Y-193856D01*
X264866Y-192689D01*
X266613Y-192397D01*
X268359Y-192689D01*
X269888Y-193856D01*
X271198Y-195605D01*
X272072Y-197647D01*
X272508Y-199980D01*
Y-202314D01*
X272072Y-204647D01*
X271198Y-206689D01*
X269888Y-208439D01*
X268359Y-209605D01*
X266613Y-209897D01*
G01X278654D02*
X284113Y-192397D01*
X289572Y-209897D01*
G01X287606Y-203772D02*
X280619D01*
G01X297246Y-209897D02*
Y-192397D01*
X302705D01*
X304451Y-193272D01*
X305543Y-194439D01*
X305980Y-196772D01*
X305543Y-199106D01*
X304233Y-200564D01*
X302705Y-201439D01*
X297246D01*
G01X302705D02*
X305980Y-209897D01*
G01X314310D02*
Y-192397D01*
X318676D01*
X320423Y-193272D01*
X321733Y-194439D01*
X322825Y-196188D01*
X323698Y-198231D01*
X323916Y-201147D01*
X323698Y-204064D01*
X322825Y-206106D01*
X321733Y-207856D01*
X320423Y-209022D01*
X318676Y-209897D01*
X314310D01*
G01X94686Y-164897D02*
Y-147397D01*
X100363Y-161980D01*
X106040Y-147397D01*
Y-164897D01*
G01X117863D02*
X116553Y-164605D01*
X115243Y-163439D01*
X114369Y-161397D01*
X113933Y-159064D01*
X114369Y-156730D01*
X115243Y-154689D01*
X116553Y-153522D01*
X117863Y-153231D01*
X119173Y-153522D01*
X120483Y-154689D01*
X121356Y-156730D01*
X121575Y-159064D01*
X121356Y-161397D01*
X120483Y-163439D01*
X119173Y-164605D01*
X117863Y-164897D01*
G01X139293Y-147397D02*
Y-164897D01*
G01Y-162273D02*
X138420Y-163731D01*
X137109Y-164605D01*
X135581Y-164897D01*
X133835Y-164314D01*
X132525Y-162856D01*
X131651Y-161106D01*
X131433Y-159064D01*
X131651Y-157022D01*
X132525Y-155272D01*
X133835Y-153814D01*
X135581Y-153231D01*
X137109Y-153522D01*
X138201Y-154106D01*
X139293Y-155272D01*
G01X149588Y-157022D02*
X156575D01*
X155920Y-154980D01*
X154828Y-153814D01*
X153300Y-153231D01*
X151771Y-153522D01*
X150461Y-154397D01*
X149588Y-156439D01*
X149151Y-158189D01*
Y-159939D01*
X149588Y-161689D01*
X150680Y-163439D01*
X151990Y-164605D01*
X153518Y-164897D01*
X155046Y-164314D01*
X156575Y-162564D01*
G01X170363Y-164897D02*
Y-147397D01*
G01X376163Y-209897D02*
Y-192397D01*
X373543Y-195897D01*
G01Y-209897D02*
X378783D01*
G01X389515Y-195314D02*
X390825Y-193564D01*
X392353Y-192689D01*
X394100Y-192397D01*
X396283Y-192980D01*
X397811Y-194439D01*
X398248Y-196188D01*
X398030Y-197939D01*
X397156Y-199397D01*
X392790Y-202314D01*
X390825Y-204355D01*
X389515Y-207273D01*
X389078Y-209897D01*
X398248D01*
G01X413783D02*
Y-192397D01*
X405704Y-204939D01*
X416622D01*
G01X423860Y-206397D02*
X425169Y-208439D01*
X426916Y-209605D01*
X428881Y-209897D01*
X430628Y-209605D01*
X432375Y-208147D01*
X433466Y-206397D01*
X433685Y-204647D01*
X433248Y-202606D01*
X431720Y-201147D01*
X430191Y-200564D01*
X428226D01*
G01X430191D02*
X431501Y-199689D01*
X432593Y-198231D01*
X433030Y-196481D01*
X432593Y-194730D01*
X431501Y-193272D01*
X429536Y-192397D01*
X427571Y-192689D01*
X425606Y-193856D01*
G01X442015Y-195314D02*
X443325Y-193564D01*
X444853Y-192689D01*
X446600Y-192397D01*
X448783Y-192980D01*
X450311Y-194439D01*
X450748Y-196188D01*
X450530Y-197939D01*
X449656Y-199397D01*
X445290Y-202314D01*
X443325Y-204355D01*
X442015Y-207273D01*
X441578Y-209897D01*
X450748D01*
G01X363046Y-164897D02*
Y-147397D01*
X368286D01*
X370033Y-148272D01*
X371343Y-150314D01*
X371780Y-152647D01*
X371343Y-154980D01*
X370251Y-156730D01*
X368286Y-157606D01*
X363046D01*
G01X389716Y-148856D02*
X388406Y-147980D01*
X386878Y-147397D01*
X385131D01*
X383166Y-148272D01*
X381638Y-149730D01*
X380546Y-151481D01*
X379673Y-154397D01*
X379454Y-157022D01*
X379891Y-159647D01*
X380546Y-161397D01*
X381856Y-163147D01*
X383385Y-164314D01*
X384913Y-164897D01*
X386441D01*
X387970Y-164314D01*
X389280Y-163439D01*
X390372Y-162273D01*
G01X404159Y-155564D02*
X405033Y-154689D01*
X405688Y-153231D01*
X406125Y-151188D01*
X405688Y-149439D01*
X404815Y-148272D01*
X403286Y-147397D01*
X397391D01*
Y-164897D01*
X404596D01*
X406125Y-163731D01*
X406998Y-161980D01*
X407435Y-159939D01*
X406998Y-157897D01*
X405688Y-156147D01*
X404159Y-155564D01*
X397391D01*
G01X413363Y-170730D02*
X426463D01*
G01X432391Y-164897D02*
Y-147397D01*
X442435Y-164897D01*
Y-147397D01*
G01X454913Y-164897D02*
X453166Y-164605D01*
X451638Y-163439D01*
X450328Y-161689D01*
X449454Y-159647D01*
X449018Y-157314D01*
Y-154980D01*
X449454Y-152647D01*
X450328Y-150605D01*
X451638Y-148856D01*
X453166Y-147689D01*
X454913Y-147397D01*
X456659Y-147689D01*
X458188Y-148856D01*
X459498Y-150605D01*
X460372Y-152647D01*
X460808Y-154980D01*
Y-157314D01*
X460372Y-159647D01*
X459498Y-161689D01*
X458188Y-163439D01*
X456659Y-164605D01*
X454913Y-164897D01*
G01X505754Y-147397D02*
X511213Y-164897D01*
X516672Y-147397D01*
G01X533080Y-164897D02*
X524346D01*
Y-147397D01*
X533080D01*
G01X529586Y-155855D02*
X524346D01*
G01X541846Y-164897D02*
Y-147397D01*
X547305D01*
X549051Y-148272D01*
X550143Y-149439D01*
X550580Y-151772D01*
X550143Y-154106D01*
X548833Y-155564D01*
X547305Y-156439D01*
X541846D01*
G01X547305D02*
X550580Y-164897D01*
G01X563713Y-165480D02*
X563276Y-165189D01*
Y-164605D01*
X563713Y-164314D01*
X564150Y-164605D01*
Y-165189D01*
X563713Y-165480D01*
G01X537463Y-209897D02*
Y-192397D01*
X534843Y-195897D01*
G01Y-209897D02*
X540083D01*
G01X630546Y-147397D02*
Y-164897D01*
X639280D01*
G01X656343D02*
Y-153231D01*
G01Y-155272D02*
X655470Y-154106D01*
X654159Y-153522D01*
X652631Y-153231D01*
X651103Y-153814D01*
X649793Y-154980D01*
X648919Y-156730D01*
X648483Y-159064D01*
X648919Y-161397D01*
X649793Y-163147D01*
X651103Y-164314D01*
X652631Y-164897D01*
X654159Y-164605D01*
X655470Y-163731D01*
X656343Y-162564D01*
G01X665328Y-170147D02*
X666638Y-170730D01*
X668385Y-170147D01*
X669476Y-168981D01*
X670350Y-167522D01*
X671659Y-162856D01*
X674498Y-153231D01*
G01X667511D02*
X671659Y-162856D01*
G01X684138Y-157022D02*
X691125D01*
X690470Y-154980D01*
X689378Y-153814D01*
X687850Y-153231D01*
X686321Y-153522D01*
X685011Y-154397D01*
X684138Y-156439D01*
X683701Y-158189D01*
Y-159939D01*
X684138Y-161689D01*
X685230Y-163439D01*
X686540Y-164605D01*
X688068Y-164897D01*
X689596Y-164314D01*
X691125Y-162564D01*
G01X701856Y-164897D02*
Y-153231D01*
G01Y-155564D02*
X702948Y-154397D01*
X704040Y-153522D01*
X705568Y-153231D01*
X706659Y-153522D01*
X707970Y-154397D01*
G01X719138Y-162856D02*
X720230Y-164022D01*
X721758Y-164897D01*
X723068D01*
X724378Y-164314D01*
X725251Y-163439D01*
X725688Y-162273D01*
X725470Y-160522D01*
X724596Y-159647D01*
X720666Y-157897D01*
X719793Y-155855D01*
X720230Y-154397D01*
X721103Y-153522D01*
X722413Y-153231D01*
X723723Y-153522D01*
X725033Y-154397D01*
G01X691780Y-192397D02*
Y-209897D01*
X683046D01*
G01X669913D02*
X668385Y-209605D01*
X666638Y-208731D01*
X665546Y-207273D01*
X665110Y-205230D01*
X665546Y-203189D01*
X666856Y-201439D01*
X668821Y-200564D01*
X671005D01*
X672315Y-199980D01*
X673407Y-198522D01*
X673843Y-196481D01*
X673188Y-194439D01*
X671660Y-192980D01*
X669913Y-192397D01*
X668167Y-192980D01*
X666638Y-194439D01*
X665983Y-196481D01*
X666420Y-198522D01*
X667511Y-199980D01*
X668821Y-200564D01*
X671005D01*
X672970Y-201439D01*
X674280Y-203189D01*
X674716Y-205230D01*
X674280Y-207273D01*
X673188Y-208731D01*
X671441Y-209605D01*
X669913Y-209897D01*
G01X781410Y-164897D02*
Y-147397D01*
X785776D01*
X787523Y-148272D01*
X788833Y-149439D01*
X789925Y-151188D01*
X790798Y-153231D01*
X791016Y-156147D01*
X790798Y-159064D01*
X789925Y-161106D01*
X788833Y-162856D01*
X787523Y-164022D01*
X785776Y-164897D01*
X781410D01*
G01X800438Y-157022D02*
X807425D01*
X806770Y-154980D01*
X805678Y-153814D01*
X804150Y-153231D01*
X802621Y-153522D01*
X801311Y-154397D01*
X800438Y-156439D01*
X800001Y-158189D01*
Y-159939D01*
X800438Y-161689D01*
X801530Y-163439D01*
X802840Y-164605D01*
X804368Y-164897D01*
X805896Y-164314D01*
X807425Y-162564D01*
G01X817938Y-162856D02*
X819030Y-164022D01*
X820558Y-164897D01*
X821868D01*
X823178Y-164314D01*
X824051Y-163439D01*
X824488Y-162273D01*
X824270Y-160522D01*
X823396Y-159647D01*
X819466Y-157897D01*
X818593Y-155855D01*
X819030Y-154397D01*
X819903Y-153522D01*
X821213Y-153231D01*
X822523Y-153522D01*
X823833Y-154397D01*
G01X838713Y-153231D02*
Y-164897D01*
G01Y-148564D02*
X838276Y-148272D01*
Y-147689D01*
X838713Y-147397D01*
X839150Y-147689D01*
Y-148272D01*
X838713Y-148564D01*
G01X853156Y-169272D02*
X854685Y-170439D01*
X856431Y-170730D01*
X857959Y-170439D01*
X859270Y-168981D01*
X860143Y-166939D01*
Y-153231D01*
G01Y-155564D02*
X859270Y-154397D01*
X857959Y-153522D01*
X856431Y-153231D01*
X854685Y-153814D01*
X853593Y-154980D01*
X852719Y-157022D01*
X852283Y-159064D01*
X852501Y-160814D01*
X853375Y-162856D01*
X854685Y-164314D01*
X856431Y-164897D01*
X857741Y-164605D01*
X859270Y-163439D01*
X860143Y-162273D01*
G01X870001Y-164897D02*
Y-153231D01*
G01Y-156147D02*
X870875Y-154689D01*
X872185Y-153522D01*
X873931Y-153231D01*
X875459Y-153522D01*
X876770Y-154689D01*
X877425Y-156730D01*
Y-164897D01*
G01X887938Y-157022D02*
X894925D01*
X894270Y-154980D01*
X893178Y-153814D01*
X891650Y-153231D01*
X890121Y-153522D01*
X888811Y-154397D01*
X887938Y-156439D01*
X887501Y-158189D01*
Y-159939D01*
X887938Y-161689D01*
X889030Y-163439D01*
X890340Y-164605D01*
X891868Y-164897D01*
X893396Y-164314D01*
X894925Y-162564D01*
G01X905656Y-164897D02*
Y-153231D01*
G01Y-155564D02*
X906748Y-154397D01*
X907840Y-153522D01*
X909368Y-153231D01*
X910459Y-153522D01*
X911770Y-154397D01*
G01X825596Y-209897D02*
Y-192397D01*
X831055D01*
X832801Y-193272D01*
X833893Y-194439D01*
X834330Y-196772D01*
X833893Y-199106D01*
X832583Y-200564D01*
X831055Y-201439D01*
X825596D01*
G01X831055D02*
X834330Y-209897D01*
G01X847463D02*
X846153Y-209605D01*
X844843Y-208439D01*
X843969Y-206397D01*
X843533Y-204064D01*
X843969Y-201730D01*
X844843Y-199689D01*
X846153Y-198522D01*
X847463Y-198231D01*
X848773Y-198522D01*
X850083Y-199689D01*
X850956Y-201730D01*
X851175Y-204064D01*
X850956Y-206397D01*
X850083Y-208439D01*
X848773Y-209605D01*
X847463Y-209897D01*
G01X861033D02*
Y-192397D01*
G01Y-201147D02*
X862125Y-199397D01*
X863435Y-198522D01*
X864745Y-198231D01*
X866709Y-198814D01*
X868020Y-199980D01*
X868893Y-202022D01*
Y-204355D01*
X868456Y-206689D01*
X867583Y-208439D01*
X866055Y-209605D01*
X864745Y-209897D01*
X863435Y-209605D01*
X862125Y-208731D01*
X861033Y-207273D01*
G01X952413Y-209897D02*
Y-192397D01*
X949793Y-195897D01*
G01Y-209897D02*
X955033D01*
G01X969913Y-192397D02*
X968166Y-192980D01*
X966856Y-194439D01*
X965983Y-196188D01*
X965328Y-198522D01*
X965110Y-201147D01*
X965328Y-203772D01*
X965983Y-206106D01*
X966856Y-207856D01*
X968166Y-209314D01*
X969913Y-209897D01*
X971659Y-209314D01*
X972970Y-207856D01*
X973843Y-206106D01*
X974498Y-203772D01*
X974716Y-201147D01*
X974498Y-198522D01*
X973843Y-196188D01*
X972970Y-194439D01*
X971659Y-192980D01*
X969913Y-192397D01*
G01X983483Y-210480D02*
X991343Y-192397D01*
G01X1004913Y-209897D02*
Y-192397D01*
X1002293Y-195897D01*
G01Y-209897D02*
X1007533D01*
G01X1018265Y-202606D02*
X1019793Y-200564D01*
X1021103Y-199397D01*
X1022850Y-198814D01*
X1024378Y-199397D01*
X1025470Y-200564D01*
X1026343Y-202314D01*
X1026561Y-204355D01*
X1026343Y-206106D01*
X1025470Y-207856D01*
X1024159Y-209314D01*
X1022631Y-209897D01*
X1020885Y-209314D01*
X1019356Y-207564D01*
X1018483Y-204939D01*
X1018265Y-202022D01*
X1018701Y-198231D01*
X1019356Y-196188D01*
X1020448Y-194147D01*
X1021976Y-192689D01*
X1023505Y-192397D01*
X1025033Y-192980D01*
X1026125Y-194439D01*
G01X1035983Y-210480D02*
X1043843Y-192397D01*
G01X1053265Y-195314D02*
X1054575Y-193564D01*
X1056103Y-192689D01*
X1057850Y-192397D01*
X1060033Y-192980D01*
X1061561Y-194439D01*
X1061998Y-196188D01*
X1061780Y-197939D01*
X1060906Y-199397D01*
X1056540Y-202314D01*
X1054575Y-204355D01*
X1053265Y-207273D01*
X1052828Y-209897D01*
X1061998D01*
G01X1074913Y-192397D02*
X1073166Y-192980D01*
X1071856Y-194439D01*
X1070983Y-196188D01*
X1070328Y-198522D01*
X1070110Y-201147D01*
X1070328Y-203772D01*
X1070983Y-206106D01*
X1071856Y-207856D01*
X1073166Y-209314D01*
X1074913Y-209897D01*
X1076659Y-209314D01*
X1077970Y-207856D01*
X1078843Y-206106D01*
X1079498Y-203772D01*
X1079716Y-201147D01*
X1079498Y-198522D01*
X1078843Y-196188D01*
X1077970Y-194439D01*
X1076659Y-192980D01*
X1074913Y-192397D01*
G01X1092413Y-209897D02*
Y-192397D01*
X1089793Y-195897D01*
G01Y-209897D02*
X1095033D01*
G01X1105765Y-195314D02*
X1107075Y-193564D01*
X1108603Y-192689D01*
X1110350Y-192397D01*
X1112533Y-192980D01*
X1114061Y-194439D01*
X1114498Y-196188D01*
X1114280Y-197939D01*
X1113406Y-199397D01*
X1109040Y-202314D01*
X1107075Y-204355D01*
X1105765Y-207273D01*
X1105328Y-209897D01*
X1114498D01*
G01X1000110Y-164897D02*
Y-147397D01*
X1004476D01*
X1006223Y-148272D01*
X1007533Y-149439D01*
X1008625Y-151188D01*
X1009498Y-153231D01*
X1009716Y-156147D01*
X1009498Y-159064D01*
X1008625Y-161106D01*
X1007533Y-162856D01*
X1006223Y-164022D01*
X1004476Y-164897D01*
X1000110D01*
G01X1026343D02*
Y-153231D01*
G01Y-155272D02*
X1025470Y-154106D01*
X1024159Y-153522D01*
X1022631Y-153231D01*
X1021103Y-153814D01*
X1019793Y-154980D01*
X1018919Y-156730D01*
X1018483Y-159064D01*
X1018919Y-161397D01*
X1019793Y-163147D01*
X1021103Y-164314D01*
X1022631Y-164897D01*
X1024159Y-164605D01*
X1025470Y-163731D01*
X1026343Y-162564D01*
G01X1039913Y-147397D02*
Y-164897D01*
G01X1036856Y-153231D02*
X1042970D01*
G01X1054138Y-157022D02*
X1061125D01*
X1060470Y-154980D01*
X1059378Y-153814D01*
X1057850Y-153231D01*
X1056321Y-153522D01*
X1055011Y-154397D01*
X1054138Y-156439D01*
X1053701Y-158189D01*
Y-159939D01*
X1054138Y-161689D01*
X1055230Y-163439D01*
X1056540Y-164605D01*
X1058068Y-164897D01*
X1059596Y-164314D01*
X1061125Y-162564D01*
G54D17*
X986308Y1447976D03*
Y1460976D03*
Y1456976D03*
Y1487976D03*
Y1500976D03*
Y1496976D03*
Y1526976D03*
Y1540976D03*
Y1536976D03*
Y1566976D03*
Y1582976D03*
Y1577976D03*
X999107Y1605976D03*
G54D18*
X997608Y1452322D03*
Y1492322D03*
Y1532322D03*
Y1572322D03*
G54D19*
X997607Y1602322D03*
M02*
